G04 ================== begin FILE IDENTIFICATION RECORD ==================*
G04 Layout Name:  15126-1b.brd*
G04 Film Name:    TMASK*
G04 File Format:  Gerber RS274X*
G04 File Origin:  Cadence Allegro 16.6-2015-S079*
G04 Origin Date:  Fri Feb 10 17:21:52 2017*
G04 *
G04 Layer:  VIA CLASS/SOLDERMASK_TOP*
G04 Layer:  PIN/SOLDERMASK_TOP*
G04 Layer:  PACKAGE GEOMETRY/SOLDERMASK_TOP*
G04 Layer:  DRAWING FORMAT/LAYER_SOLDER_T*
G04 Layer:  BOARD GEOMETRY/SOLDERMASK_TOP*
G04 Layer:  DRAWING FORMAT/LAYER_PCB_STORY*
G04 *
G04 Offset:    (0.00 0.00)*
G04 Mirror:    No*
G04 Mode:      Positive*
G04 Rotation:  0*
G04 FullContactRelief:  No*
G04 UndefLineWidth:     6.00*
G04 ================== end FILE IDENTIFICATION RECORD ====================*
%FSLAX35Y35*MOIN*%
%IR0*IPPOS*OFA0.00000B0.00000*MIA0B0*SFA1.00000B1.00000*%
%AMMACRO202*
4,1,40,.017,-.013,
.017,.013,
.016939,.013695,
.016759,.014368,
.016464,.015,
.016064,.015571,
.015571,.016064,
.015,.016464,
.014368,.016759,
.013695,.016939,
.013,.017,
-.013,.017,
-.013695,.016939,
-.014368,.016759,
-.015,.016464,
-.015571,.016064,
-.016064,.015571,
-.016464,.015,
-.016759,.014368,
-.016939,.013695,
-.017,.013,
-.017,-.013,
-.016939,-.013695,
-.016759,-.014368,
-.016464,-.015,
-.016064,-.015571,
-.015571,-.016064,
-.015,-.016464,
-.014368,-.016759,
-.013695,-.016939,
-.013,-.017,
.013,-.017,
.013695,-.016939,
.014368,-.016759,
.015,-.016464,
.015571,-.016064,
.016064,-.015571,
.016464,-.015,
.016759,-.014368,
.016939,-.013695,
.017,-.013,
0.0*
%
%ADD202MACRO202*%
%AMMACRO36*
4,1,40,.013,.017,
-.013,.017,
-.013695,.016939,
-.014368,.016759,
-.015,.016464,
-.015571,.016064,
-.016064,.015571,
-.016464,.015,
-.016759,.014368,
-.016939,.013695,
-.017,.013,
-.017,-.013,
-.016939,-.013695,
-.016759,-.014368,
-.016464,-.015,
-.016064,-.015571,
-.015571,-.016064,
-.015,-.016464,
-.014368,-.016759,
-.013695,-.016939,
-.013,-.017,
.013,-.017,
.013695,-.016939,
.014368,-.016759,
.015,-.016464,
.015571,-.016064,
.016064,-.015571,
.016464,-.015,
.016759,-.014368,
.016939,-.013695,
.017,-.013,
.017,.013,
.016939,.013695,
.016759,.014368,
.016464,.015,
.016064,.015571,
.015571,.016064,
.015,.016464,
.014368,.016759,
.013695,.016939,
.013,.017,
0.0*
%
%ADD36MACRO36*%
%AMMACRO140*
4,1,6,-.0425,.1065,
.0145,.1065,
.0145,.0365,
.0425,.0365,
.0425,-.1065,
-.0425,-.1065,
-.0425,.1065,
0.0*
%
%ADD140MACRO140*%
%AMMACRO273*
4,1,21,.006,.015,
.006,-.009,
.005909,-.010042,
.005638,-.011052,
.005196,-.012,
.004596,-.012857,
.003857,-.013596,
.003,-.014196,
.002052,-.014638,
.001042,-.014909,
0.0,-.015,
-.001042,-.014909,
-.002052,-.014638,
-.003,-.014196,
-.003857,-.013596,
-.004596,-.012857,
-.005196,-.012,
-.005638,-.011052,
-.005909,-.010042,
-.006,-.009,
-.006,.015,
.006,.015,
0.0*
%
%ADD273MACRO273*%
%ADD116O,.062X.111*%
%AMMACRO186*
21,1,.02,.007,0.0,0.0,.1*%
%ADD186MACRO186*%
%ADD318R,.05X.115*%
%ADD15R,.09X.12*%
%AMMACRO302*
4,1,12,.0325,.0195,
-.0325,.0195,
-.0325,-.0195,
-.0195,-.0195,
-.0195,.0005,
-.0065,.0005,
-.0065,-.0195,
.0065,-.0195,
.0065,.0005,
.0195,.0005,
.0195,-.0195,
.0325,-.0195,
.0325,.0195,
0.0*
%
%ADD302MACRO302*%
%AMMACRO198*
21,1,.02,.007,0.0,0.0,12.5*%
%ADD198MACRO198*%
%ADD108R,.12X.09*%
%ADD97R,.135X.031*%
%ADD298R,.108X.04*%
%ADD266R,.055X.13*%
%ADD126R,.02X.007*%
%AMMACRO124*
21,1,.007,.02,0.0,0.0,45.*%
%ADD124MACRO124*%
%ADD102R,.11X.039*%
%ADD82R,.031X.135*%
%AMMACRO63*
21,1,.02,.007,0.0,0.0,45.*%
%ADD63MACRO63*%
%ADD48R,.007X.02*%
%ADD286R,.138X.02*%
%AMMACRO243*
21,1,.02,.007,0.0,0.0,45.1*%
%ADD243MACRO243*%
%AMMACRO201*
21,1,.02,.007,0.0,0.0,11.503*%
%ADD201MACRO201*%
%ADD125R,.007X.02*%
%AMMACRO93*
4,1,21,.006,-.014,
-.006,-.014,
-.006,.008,
-.005909,.009042,
-.005638,.010052,
-.005196,.011,
-.004596,.011857,
-.003857,.012596,
-.003,.013196,
-.002052,.013638,
-.001042,.013909,
0.0,.014,
.001042,.013909,
.002052,.013638,
.003,.013196,
.003857,.012596,
.004596,.011857,
.005196,.011,
.005638,.010052,
.005909,.009042,
.006,.008,
.006,-.014,
0.0*
%
%ADD93MACRO93*%
%ADD71R,.02X.007*%
%ADD59R,.134X.024*%
%ADD41R,.024X.171*%
%ADD11R,.053X.106*%
%ADD219R,.171X.024*%
%AMMACRO187*
21,1,.02,.007,0.0,0.0,35.3*%
%ADD187MACRO187*%
%ADD28C,.02*%
%ADD114C,.012*%
%ADD23C,.03*%
%AMMACRO274*
4,1,21,.015,-.006,
-.009,-.006,
-.010042,-.005909,
-.011052,-.005638,
-.012,-.005196,
-.012857,-.004596,
-.013596,-.003857,
-.014196,-.003,
-.014638,-.002052,
-.014909,-.001042,
-.015,0.0,
-.014909,.001042,
-.014638,.002052,
-.014196,.003,
-.013596,.003857,
-.012857,.004596,
-.012,.005196,
-.011052,.005638,
-.010042,.005909,
-.009,.006,
.015,.006,
.015,-.006,
0.0*
%
%ADD274MACRO274*%
%ADD257C,.04*%
%ADD249C,.031*%
%AMMACRO174*
21,1,.02,.007,0.0,0.0,37.003*%
%ADD174MACRO174*%
%ADD305R,.014X.008*%
%ADD184C,.05*%
%AMMACRO170*
21,1,.02,.007,0.0,0.0,45.104*%
%ADD170MACRO170*%
%ADD19C,.014*%
%ADD14C,.032*%
%ADD213C,.015*%
%ADD209R,.108X.047*%
%ADD189R,.063X.118*%
%AMMACRO175*
21,1,.02,.007,0.0,0.0,37.014*%
%ADD175MACRO175*%
%AMMACRO171*
21,1,.02,.007,0.0,0.0,34.044*%
%ADD171MACRO171*%
%ADD58R,.134X.047*%
%ADD26C,.06*%
%ADD281C,.052*%
%ADD216C,.016*%
%ADD122C,.025*%
%ADD13C,.034*%
%AMMACRO287*
4,1,6,-.0475,-.0155,
-.0475,.0445,
.0475,.0445,
.0475,-.0445,
-.0235,-.0445,
-.0235,-.0155,
-.0475,-.0155,
0.0*
%
%ADD287MACRO287*%
%ADD276R,.094X.207*%
%ADD263C,.062*%
%AMMACRO194*
21,1,.02,.007,0.0,0.0,44.9*%
%ADD194MACRO194*%
%ADD112C,.017*%
%ADD105C,.026*%
%ADD55C,.044*%
%ADD27C,.08*%
%ADD16C,.071*%
%ADD211C,.063*%
%ADD195C,.054*%
%AMMACRO176*
21,1,.02,.007,0.0,0.0,40.554*%
%ADD176MACRO176*%
%ADD80C,.045*%
%ADD56C,.036*%
%ADD295C,.055*%
%AMMACRO272*
4,1,21,-.015,.006,
.009,.006,
.010042,.005909,
.011052,.005638,
.012,.005196,
.012857,.004596,
.013596,.003857,
.014196,.003,
.014638,.002052,
.014909,.001042,
.015,0.0,
.014909,-.001042,
.014638,-.002052,
.014196,-.003,
.013596,-.003857,
.012857,-.004596,
.012,-.005196,
.011052,-.005638,
.010042,-.005909,
.009,-.006,
-.015,-.006,
-.015,.006,
0.0*
%
%ADD272MACRO272*%
%ADD244C,.037*%
%ADD190C,.064*%
%AMMACRO172*
21,1,.02,.007,0.0,0.0,21.79*%
%ADD172MACRO172*%
%AMMACRO104*
4,1,8,-.0585,.0725,
-.0585,-.0725,
.0585,-.0725,
.0585,-.04275,
.0185,-.04275,
.0185,.04275,
.0585,.04275,
.0585,.0725,
-.0585,.0725,
0.0*
%
%ADD104MACRO104*%
%ADD61C,.046*%
%ADD301R,.173X.059*%
%ADD288R,.013X.013*%
%ADD264C,.047*%
%ADD259R,.031X.031*%
%ADD208C,.056*%
%AMMACRO203*
4,1,21,.01,.004,
.010695,.003939,
.011368,.003759,
.012,.003464,
.012571,.003064,
.013064,.002571,
.013464,.002,
.013759,.001368,
.013939,.000695,
.014,0.0,
.013939,-.000695,
.013759,-.001368,
.013464,-.002,
.013064,-.002571,
.012571,-.003064,
.012,-.003464,
.011368,-.003759,
.010695,-.003939,
.01,-.004,
-.014,-.004,
-.014,.004,
.01,.004,
0.0*
%
%ADD203MACRO203*%
%ADD123C,.065*%
%ADD107R,.075X.165*%
%AMMACRO94*
4,1,21,-.014,-.006,
-.014,.006,
.008,.006,
.009042,.005909,
.010052,.005638,
.011,.005196,
.011857,.004596,
.012596,.003857,
.013196,.003,
.013638,.002052,
.013909,.001042,
.014,0.0,
.013909,-.001042,
.013638,-.002052,
.013196,-.003,
.012596,-.003857,
.011857,-.004596,
.011,-.005196,
.010052,-.005638,
.009042,-.005909,
.008,-.006,
-.014,-.006,
0.0*
%
%ADD94MACRO94*%
%ADD60C,.074*%
%ADD278R,.05X.05*%
%AMMACRO271*
4,1,21,-.006,-.015,
-.006,.009,
-.005909,.010042,
-.005638,.011052,
-.005196,.012,
-.004596,.012857,
-.003857,.013596,
-.003,.014196,
-.002052,.014638,
-.001042,.014909,
0.0,.015,
.001042,.014909,
.002052,.014638,
.003,.014196,
.003857,.013596,
.004596,.012857,
.005196,.012,
.005638,.011052,
.005909,.010042,
.006,.009,
.006,-.015,
-.006,-.015,
0.0*
%
%ADD271MACRO271*%
%AMMACRO173*
21,1,.02,.007,0.0,0.0,34.77*%
%ADD173MACRO173*%
%AMMACRO169*
21,1,.02,.007,0.0,0.0,33.645*%
%ADD169MACRO169*%
%AMMACRO98*
4,1,21,.004,-.01,
.003939,-.010695,
.003759,-.011368,
.003464,-.012,
.003064,-.012571,
.002571,-.013064,
.002,-.013464,
.001368,-.013759,
.000695,-.013939,
0.0,-.014,
-.000695,-.013939,
-.001368,-.013759,
-.002,-.013464,
-.002571,-.013064,
-.003064,-.012571,
-.003464,-.012,
-.003759,-.011368,
-.003939,-.010695,
-.004,-.01,
-.004,.014,
.004,.014,
.004,-.01,
0.0*
%
%ADD98MACRO98*%
%ADD77C,.039*%
%ADD72C,.057*%
%ADD52C,.084*%
%ADD25R,.06X.06*%
%ADD24C,.086*%
%ADD325R,.035X.035*%
%ADD252C,.069*%
%ADD297R,.045X.045*%
%ADD250R,.054X.054*%
%ADD317R,.055X.055*%
%ADD191R,.064X.064*%
%AMMACRO96*
4,1,21,.014,.006,
.014,-.006,
-.008,-.006,
-.009042,-.005909,
-.010052,-.005638,
-.011,-.005196,
-.011857,-.004596,
-.012596,-.003857,
-.013196,-.003,
-.013638,-.002052,
-.013909,-.001042,
-.014,0.0,
-.013909,.001042,
-.013638,.002052,
-.013196,.003,
-.012596,.003857,
-.011857,.004596,
-.011,.005196,
-.010052,.005638,
-.009042,.005909,
-.008,.006,
.014,.006,
0.0*
%
%ADD96MACRO96*%
%ADD300R,.047X.047*%
%AMMACRO147*
4,1,40,.011,-.007,
.011,.007,
.010939,.007695,
.010759,.008368,
.010464,.009,
.010064,.009571,
.009571,.010064,
.009,.010464,
.008368,.010759,
.007695,.010939,
.007,.011,
-.007,.011,
-.007695,.010939,
-.008368,.010759,
-.009,.010464,
-.009571,.010064,
-.010064,.009571,
-.010464,.009,
-.010759,.008368,
-.010939,.007695,
-.011,.007,
-.011,-.007,
-.010939,-.007695,
-.010759,-.008368,
-.010464,-.009,
-.010064,-.009571,
-.009571,-.010064,
-.009,-.010464,
-.008368,-.010759,
-.007695,-.010939,
-.007,-.011,
.007,-.011,
.007695,-.010939,
.008368,-.010759,
.009,-.010464,
.009571,-.010064,
.010064,-.009571,
.010464,-.009,
.010759,-.008368,
.010939,-.007695,
.011,-.007,
0.0*
%
%ADD147MACRO147*%
%AMMACRO29*
4,1,40,.007,.011,
-.007,.011,
-.007695,.010939,
-.008368,.010759,
-.009,.010464,
-.009571,.010064,
-.010064,.009571,
-.010464,.009,
-.010759,.008368,
-.010939,.007695,
-.011,.007,
-.011,-.007,
-.010939,-.007695,
-.010759,-.008368,
-.010464,-.009,
-.010064,-.009571,
-.009571,-.010064,
-.009,-.010464,
-.008368,-.010759,
-.007695,-.010939,
-.007,-.011,
.007,-.011,
.007695,-.010939,
.008368,-.010759,
.009,-.010464,
.009571,-.010064,
.010064,-.009571,
.010464,-.009,
.010759,-.008368,
.010939,-.007695,
.011,-.007,
.011,.007,
.010939,.007695,
.010759,.008368,
.010464,.009,
.010064,.009571,
.009571,.010064,
.009,.010464,
.008368,.010759,
.007695,.010939,
.007,.011,
0.0*
%
%ADD29MACRO29*%
%AMMACRO95*
4,1,21,-.006,.014,
.006,.014,
.006,-.008,
.005909,-.009042,
.005638,-.010052,
.005196,-.011,
.004596,-.011857,
.003857,-.012596,
.003,-.013196,
.002052,-.013638,
.001042,-.013909,
0.0,-.014,
-.001042,-.013909,
-.002052,-.013638,
-.003,-.013196,
-.003857,-.012596,
-.004596,-.011857,
-.005196,-.011,
-.005638,-.010052,
-.005909,-.009042,
-.006,-.008,
-.006,.014,
0.0*
%
%ADD95MACRO95*%
%ADD78R,.039X.039*%
%AMMACRO204*
4,1,21,.004,-.01,
.003939,-.010695,
.003759,-.011368,
.003464,-.012,
.003064,-.012571,
.002571,-.013064,
.002,-.013464,
.001368,-.013759,
.000695,-.013939,
0.0,-.014,
-.000695,-.013939,
-.001368,-.013759,
-.002,-.013464,
-.002571,-.013064,
-.003064,-.012571,
-.003464,-.012,
-.003759,-.011368,
-.003939,-.010695,
-.004,-.01,
-.004,.014,
.004,.014,
.004,-.01,
0.0*
%
%ADD204MACRO204*%
%AMMACRO99*
4,1,21,-.01,-.004,
-.010695,-.003939,
-.011368,-.003759,
-.012,-.003464,
-.012571,-.003064,
-.013064,-.002571,
-.013464,-.002,
-.013759,-.001368,
-.013939,-.000695,
-.014,0.0,
-.013939,.000695,
-.013759,.001368,
-.013464,.002,
-.013064,.002571,
-.012571,.003064,
-.012,.003464,
-.011368,.003759,
-.010695,.003939,
-.01,.004,
.014,.004,
.014,-.004,
-.01,-.004,
0.0*
%
%ADD99MACRO99*%
%AMMACRO31*
4,1,40,-.012,.008,
-.012,-.008,
-.011939,-.008695,
-.011759,-.009368,
-.011464,-.01,
-.011064,-.010571,
-.010571,-.011064,
-.01,-.011464,
-.009368,-.011759,
-.008695,-.011939,
-.008,-.012,
.008,-.012,
.008695,-.011939,
.009368,-.011759,
.01,-.011464,
.010571,-.011064,
.011064,-.010571,
.011464,-.01,
.011759,-.009368,
.011939,-.008695,
.012,-.008,
.012,.008,
.011939,.008695,
.011759,.009368,
.011464,.01,
.011064,.010571,
.010571,.011064,
.01,.011464,
.009368,.011759,
.008695,.011939,
.008,.012,
-.008,.012,
-.008695,.011939,
-.009368,.011759,
-.01,.011464,
-.010571,.011064,
-.011064,.010571,
-.011464,.01,
-.011759,.009368,
-.011939,.008695,
-.012,.008,
0.0*
%
%ADD31MACRO31*%
%AMMACRO141*
4,1,40,-.013,-.017,
.013,-.017,
.013695,-.016939,
.014368,-.016759,
.015,-.016464,
.015571,-.016064,
.016064,-.015571,
.016464,-.015,
.016759,-.014368,
.016939,-.013695,
.017,-.013,
.017,.013,
.016939,.013695,
.016759,.014368,
.016464,.015,
.016064,.015571,
.015571,.016064,
.015,.016464,
.014368,.016759,
.013695,.016939,
.013,.017,
-.013,.017,
-.013695,.016939,
-.014368,.016759,
-.015,.016464,
-.015571,.016064,
-.016064,.015571,
-.016464,.015,
-.016759,.014368,
-.016939,.013695,
-.017,.013,
-.017,-.013,
-.016939,-.013695,
-.016759,-.014368,
-.016464,-.015,
-.016064,-.015571,
-.015571,-.016064,
-.015,-.016464,
-.014368,-.016759,
-.013695,-.016939,
-.013,-.017,
0.0*
%
%ADD141MACRO141*%
%AMMACRO311*
21,1,.02,.007,0.0,0.0,89.828*%
%ADD311MACRO311*%
%AMMACRO261*
4,1,40,-.017,.013,
-.017,-.013,
-.016939,-.013695,
-.016759,-.014368,
-.016464,-.015,
-.016064,-.015571,
-.015571,-.016064,
-.015,-.016464,
-.014368,-.016759,
-.013695,-.016939,
-.013,-.017,
.013,-.017,
.013695,-.016939,
.014368,-.016759,
.015,-.016464,
.015571,-.016064,
.016064,-.015571,
.016464,-.015,
.016759,-.014368,
.016939,-.013695,
.017,-.013,
.017,.013,
.016939,.013695,
.016759,.014368,
.016464,.015,
.016064,.015571,
.015571,.016064,
.015,.016464,
.014368,.016759,
.013695,.016939,
.013,.017,
-.013,.017,
-.013695,.016939,
-.014368,.016759,
-.015,.016464,
-.015571,.016064,
-.016064,.015571,
-.016464,.015,
-.016759,.014368,
-.016939,.013695,
-.017,.013,
0.0*
%
%ADD261MACRO261*%
%AMMACRO206*
4,1,21,-.004,.01,
-.003939,.010695,
-.003759,.011368,
-.003464,.012,
-.003064,.012571,
-.002571,.013064,
-.002,.013464,
-.001368,.013759,
-.000695,.013939,
0.0,.014,
.000695,.013939,
.001368,.013759,
.002,.013464,
.002571,.013064,
.003064,.012571,
.003464,.012,
.003759,.011368,
.003939,.010695,
.004,.01,
.004,-.014,
-.004,-.014,
-.004,.01,
0.0*
%
%ADD206MACRO206*%
%AMMACRO101*
4,1,21,.01,.004,
.010695,.003939,
.011368,.003759,
.012,.003464,
.012571,.003064,
.013064,.002571,
.013464,.002,
.013759,.001368,
.013939,.000695,
.014,0.0,
.013939,-.000695,
.013759,-.001368,
.013464,-.002,
.013064,-.002571,
.012571,-.003064,
.012,-.003464,
.011368,-.003759,
.010695,-.003939,
.01,-.004,
-.014,-.004,
-.014,.004,
.01,.004,
0.0*
%
%ADD101MACRO101*%
%AMMACRO205*
4,1,21,-.01,-.004,
-.010695,-.003939,
-.011368,-.003759,
-.012,-.003464,
-.012571,-.003064,
-.013064,-.002571,
-.013464,-.002,
-.013759,-.001368,
-.013939,-.000695,
-.014,0.0,
-.013939,.000695,
-.013759,.001368,
-.013464,.002,
-.013064,.002571,
-.012571,.003064,
-.012,.003464,
-.011368,.003759,
-.010695,.003939,
-.01,.004,
.014,.004,
.014,-.004,
-.01,-.004,
0.0*
%
%ADD205MACRO205*%
%AMMACRO100*
4,1,21,-.004,.01,
-.003939,.010695,
-.003759,.011368,
-.003464,.012,
-.003064,.012571,
-.002571,.013064,
-.002,.013464,
-.001368,.013759,
-.000695,.013939,
0.0,.014,
.000695,.013939,
.001368,.013759,
.002,.013464,
.002571,.013064,
.003064,.012571,
.003464,.012,
.003759,.011368,
.003939,.010695,
.004,.01,
.004,-.014,
-.004,-.014,
-.004,.01,
0.0*
%
%ADD100MACRO100*%
%AMMACRO148*
4,1,40,.011,-.007,
.011,.007,
.010939,.007695,
.010759,.008368,
.010464,.009,
.010064,.009571,
.009571,.010064,
.009,.010464,
.008368,.010759,
.007695,.010939,
.007,.011,
-.007,.011,
-.007695,.010939,
-.008368,.010759,
-.009,.010464,
-.009571,.010064,
-.010064,.009571,
-.010464,.009,
-.010759,.008368,
-.010939,.007695,
-.011,.007,
-.011,-.007,
-.010939,-.007695,
-.010759,-.008368,
-.010464,-.009,
-.010064,-.009571,
-.009571,-.010064,
-.009,-.010464,
-.008368,-.010759,
-.007695,-.010939,
-.007,-.011,
.007,-.011,
.007695,-.010939,
.008368,-.010759,
.009,-.010464,
.009571,-.010064,
.010064,-.009571,
.010464,-.009,
.010759,-.008368,
.010939,-.007695,
.011,-.007,
0.0*
%
%ADD148MACRO148*%
%AMMACRO30*
4,1,40,.007,.011,
-.007,.011,
-.007695,.010939,
-.008368,.010759,
-.009,.010464,
-.009571,.010064,
-.010064,.009571,
-.010464,.009,
-.010759,.008368,
-.010939,.007695,
-.011,.007,
-.011,-.007,
-.010939,-.007695,
-.010759,-.008368,
-.010464,-.009,
-.010064,-.009571,
-.009571,-.010064,
-.009,-.010464,
-.008368,-.010759,
-.007695,-.010939,
-.007,-.011,
.007,-.011,
.007695,-.010939,
.008368,-.010759,
.009,-.010464,
.009571,-.010064,
.010064,-.009571,
.010464,-.009,
.010759,-.008368,
.010939,-.007695,
.011,-.007,
.011,.007,
.010939,.007695,
.010759,.008368,
.010464,.009,
.010064,.009571,
.009571,.010064,
.009,.010464,
.008368,.010759,
.007695,.010939,
.007,.011,
0.0*
%
%ADD30MACRO30*%
%ADD119R,.12X.1*%
%ADD130R,.1X.12*%
%AMMACRO237*
4,1,13,.05895,-.0275,
.055324,-.025079,
.051332,-.023324,
.047096,-.022289,
.042745,-.022006,
.03841,-.022482,
.034225,-.023704,
.030315,-.025634,
.02765,-.0275,
-.115,-.0275,
-.115,.0275,
.115,.0275,
.115,-.0275,
.05895,-.0275,
0.0*
%
%ADD237MACRO237*%
%AMMACRO32*
4,1,40,-.012,.008,
-.012,-.008,
-.011939,-.008695,
-.011759,-.009368,
-.011464,-.01,
-.011064,-.010571,
-.010571,-.011064,
-.01,-.011464,
-.009368,-.011759,
-.008695,-.011939,
-.008,-.012,
.008,-.012,
.008695,-.011939,
.009368,-.011759,
.01,-.011464,
.010571,-.011064,
.011064,-.010571,
.011464,-.01,
.011759,-.009368,
.011939,-.008695,
.012,-.008,
.012,.008,
.011939,.008695,
.011759,.009368,
.011464,.01,
.011064,.010571,
.010571,.011064,
.01,.011464,
.009368,.011759,
.008695,.011939,
.008,.012,
-.008,.012,
-.008695,.011939,
-.009368,.011759,
-.01,.011464,
-.010571,.011064,
-.011064,.010571,
-.011464,.01,
-.011759,.009368,
-.011939,.008695,
-.012,.008,
0.0*
%
%ADD32MACRO32*%
%AMMACRO314*
4,1,11,.016,-.006,
-.016,-.006,
-.016,.006,
.01122,.006,
.011821,.004838,
.012489,.003712,
.013222,.002627,
.014016,.001587,
.014869,.000594,
.015779,-.000347,
.016,-.00056,
.016,-.006,
0.0*
%
%ADD314MACRO314*%
%ADD215O,.013X.01*%
%ADD214O,.01X.013*%
%AMMACRO142*
4,1,40,-.013,-.017,
.013,-.017,
.013695,-.016939,
.014368,-.016759,
.015,-.016464,
.015571,-.016064,
.016064,-.015571,
.016464,-.015,
.016759,-.014368,
.016939,-.013695,
.017,-.013,
.017,.013,
.016939,.013695,
.016759,.014368,
.016464,.015,
.016064,.015571,
.015571,.016064,
.015,.016464,
.014368,.016759,
.013695,.016939,
.013,.017,
-.013,.017,
-.013695,.016939,
-.014368,.016759,
-.015,.016464,
-.015571,.016064,
-.016064,.015571,
-.016464,.015,
-.016759,.014368,
-.016939,.013695,
-.017,.013,
-.017,-.013,
-.016939,-.013695,
-.016759,-.014368,
-.016464,-.015,
-.016064,-.015571,
-.015571,-.016064,
-.015,-.016464,
-.014368,-.016759,
-.013695,-.016939,
-.013,-.017,
0.0*
%
%ADD142MACRO142*%
%AMMACRO262*
4,1,40,-.017,.013,
-.017,-.013,
-.016939,-.013695,
-.016759,-.014368,
-.016464,-.015,
-.016064,-.015571,
-.015571,-.016064,
-.015,-.016464,
-.014368,-.016759,
-.013695,-.016939,
-.013,-.017,
.013,-.017,
.013695,-.016939,
.014368,-.016759,
.015,-.016464,
.015571,-.016064,
.016064,-.015571,
.016464,-.015,
.016759,-.014368,
.016939,-.013695,
.017,-.013,
.017,.013,
.016939,.013695,
.016759,.014368,
.016464,.015,
.016064,.015571,
.015571,.016064,
.015,.016464,
.014368,.016759,
.013695,.016939,
.013,.017,
-.013,.017,
-.013695,.016939,
-.014368,.016759,
-.015,.016464,
-.015571,.016064,
-.016064,.015571,
-.016464,.015,
-.016759,.014368,
-.016939,.013695,
-.017,.013,
0.0*
%
%ADD262MACRO262*%
%AMMACRO84*
4,1,8,.0825,-.065,
.0825,.065,
-.0175,.065,
-.0175,.087,
-.0825,.087,
-.0825,-.087,
-.0175,-.087,
-.0175,-.065,
.0825,-.065,
0.0*
%
%ADD84MACRO84*%
%AMMACRO40*
4,1,6,.0425,-.1065,
-.0145,-.1065,
-.0145,-.0365,
-.0425,-.0365,
-.0425,.1065,
.0425,.1065,
.0425,-.1065,
0.0*
%
%ADD40MACRO40*%
%ADD21R,.02X.02*%
%AMMACRO218*
4,1,6,-.1065,-.0425,
-.1065,.0145,
-.0365,.0145,
-.0365,.0425,
.1065,.0425,
.1065,-.0425,
-.1065,-.0425,
0.0*
%
%ADD218MACRO218*%
%ADD20R,.02X.02*%
%ADD321R,.032X.01*%
%ADD241R,.012X.03*%
%ADD240R,.03X.012*%
%AMMACRO136*
4,1,21,.0095,.0055,
.010455,.005416,
.011381,.005168,
.01225,.004763,
.013035,.004213,
.013713,.003535,
.014263,.00275,
.014668,.001881,
.014916,.000955,
.015,0.0,
.014916,-.000955,
.014668,-.001881,
.014263,-.00275,
.013713,-.003535,
.013035,-.004213,
.01225,-.004763,
.011381,-.005168,
.010455,-.005416,
.0095,-.0055,
-.015,-.0055,
-.015,.0055,
.0095,.0055,
0.0*
%
%ADD136MACRO136*%
%ADD42R,.014X.02*%
%ADD324R,.05X.03*%
%ADD310R,.032X.012*%
%ADD308O,.041X.06*%
%AMMACRO267*
4,1,12,-.0195,.0325,
-.0195,-.0325,
.0195,-.0325,
.0195,-.0195,
-.0005,-.0195,
-.0005,-.0065,
.0195,-.0065,
.0195,.0065,
-.0005,.0065,
-.0005,.0195,
.0195,.0195,
.0195,.0325,
-.0195,.0325,
0.0*
%
%ADD267MACRO267*%
%ADD220R,.02X.014*%
%AMMACRO144*
4,1,21,.015,-.006,
-.009,-.006,
-.010042,-.005909,
-.011052,-.005638,
-.012,-.005196,
-.012857,-.004596,
-.013596,-.003857,
-.014196,-.003,
-.014638,-.002052,
-.014909,-.001042,
-.015,0.0,
-.014909,.001042,
-.014638,.002052,
-.014196,.003,
-.013596,.003857,
-.012857,.004596,
-.012,.005196,
-.011052,.005638,
-.010042,.005909,
-.009,.006,
.015,.006,
.015,-.006,
0.0*
%
%ADD144MACRO144*%
%ADD121R,.125X.14*%
%ADD279R,.03X.05*%
%ADD258R,.102X.145*%
%ADD232R,.011X.033*%
%ADD231R,.033X.011*%
%AMMACRO225*
4,1,21,-.006,-.015,
-.006,.009,
-.005909,.010042,
-.005638,.011052,
-.005196,.012,
-.004596,.012857,
-.003857,.013596,
-.003,.014196,
-.002052,.014638,
-.001042,.014909,
0.0,.015,
.001042,.014909,
.002052,.014638,
.003,.014196,
.003857,.013596,
.004596,.012857,
.005196,.012,
.005638,.011052,
.005909,.010042,
.006,.009,
.006,-.015,
-.006,-.015,
0.0*
%
%ADD225MACRO225*%
%AMMACRO166*
21,1,.02,.007,0.0,0.0,153.*%
%ADD166MACRO166*%
%ADD62R,.04X.05*%
%AMMACRO47*
21,1,.02,.007,0.0,0.0,135.*%
%ADD47MACRO47*%
%AMMACRO247*
21,1,.02,.007,0.0,0.0,135.1*%
%ADD247MACRO247*%
%ADD210R,.061X.012*%
%ADD106R,.02X.071*%
%ADD90R,.015X.04*%
%ADD89R,.05X.04*%
%ADD290R,.071X.02*%
%ADD256R,.012X.026*%
%ADD217R,.105X.145*%
%AMMACRO180*
21,1,.02,.007,0.0,0.0,124.4*%
%ADD180MACRO180*%
%ADD87R,.012X.035*%
%ADD86R,.02X.045*%
%ADD85R,.06X.04*%
%ADD81R,.04X.015*%
%ADD57R,.015X.05*%
%ADD45R,.01X.028*%
%ADD44R,.028X.01*%
%ADD22R,.035X.03*%
%ADD17R,.04X.016*%
%ADD316R,.05X.015*%
%AMMACRO312*
4,1,48,.0225,.036,
.026668,.035635,
.030708,.034553,
.0345,.032785,
.037927,.030385,
.040885,.027427,
.043285,.024,
.045053,.020208,
.046135,.016168,
.0465,.012,
.046135,.007832,
.045053,.003792,
.043285,0.0,
.040885,-.003427,
.037927,-.006385,
.0345,-.008785,
.030708,-.010553,
.026668,-.011635,
.0225,-.012,
.0015,-.012,
.001135,-.016168,
.000053,-.020208,
-.001715,-.024,
-.004115,-.027427,
-.007073,-.030385,
-.0105,-.032785,
-.014292,-.034553,
-.018332,-.035635,
-.0225,-.036,
-.026668,-.035635,
-.030708,-.034553,
-.0345,-.032785,
-.037927,-.030385,
-.040885,-.027427,
-.043285,-.024,
-.045053,-.020208,
-.046135,-.016168,
-.0465,-.012,
-.0465,.012,
-.046135,.016168,
-.045053,.020208,
-.043285,.024,
-.040885,.027427,
-.037927,.030385,
-.0345,.032785,
-.030708,.034553,
-.026668,.035635,
-.0225,.036,
.0225,.036,
0.0*
%
%ADD312MACRO312*%
%ADD304R,.026X.012*%
%AMMACRO280*
21,1,.011,.09,0.0,0.0,90.001*%
%ADD280MACRO280*%
%ADD270O,.032X.036*%
%ADD254O,.126X.191*%
%ADD248C,.102*%
%ADD224R,.028X.01*%
%ADD223R,.01X.028*%
%AMMACRO183*
21,1,.02,.007,0.0,0.0,110.064*%
%ADD183MACRO183*%
%AMMACRO167*
21,1,.02,.007,0.0,0.0,153.021*%
%ADD167MACRO167*%
%AMMACRO152*
21,1,.02,.007,0.0,0.0,124.5*%
%ADD152MACRO152*%
%AMMACRO151*
21,1,.02,.007,0.0,0.0,145.2*%
%ADD151MACRO151*%
%ADD149R,.045X.02*%
%ADD132R,.012X.027*%
%ADD79R,.016X.04*%
%ADD75C,.111*%
%ADD74C,.12*%
%ADD49R,.03X.035*%
%ADD46R,.145X.105*%
%ADD18R,.014X.06*%
%ADD319R,.071X.032*%
%ADD313R,.028X.012*%
%ADD307R,.061X.024*%
%ADD277O,.191X.126*%
%ADD228R,.02X.047*%
%ADD133R,.027X.012*%
%ADD88R,.012X.037*%
%ADD296O,.07X.046*%
%AMMACRO292*
4,1,21,-.0225,.006,
.0165,.006,
.017542,.005909,
.018552,.005638,
.0195,.005196,
.020357,.004596,
.021096,.003857,
.021696,.003,
.022138,.002052,
.022409,.001042,
.0225,0.0,
.022409,-.001042,
.022138,-.002052,
.021696,-.003,
.021096,-.003857,
.020357,-.004596,
.0195,-.005196,
.018552,-.005638,
.017542,-.005909,
.0165,-.006,
-.0225,-.006,
-.0225,.006,
0.0*
%
%ADD292MACRO292*%
%ADD242R,.045X.041*%
%ADD192R,.02X.047*%
%AMMACRO179*
21,1,.02,.007,0.0,0.0,141.8*%
%ADD179MACRO179*%
%AMMACRO178*
21,1,.02,.007,0.0,0.0,142.016*%
%ADD178MACRO178*%
%AMMACRO165*
21,1,.02,.007,0.0,0.0,152.6*%
%ADD165MACRO165*%
%ADD109R,.05X.018*%
%ADD83R,.065X.02*%
%ADD53C,.14*%
%ADD265R,.02X.094*%
%AMMACRO236*
4,1,13,.05895,.0275,
.055324,.025079,
.051332,.023324,
.047096,.022289,
.042745,.022006,
.03841,.022482,
.034225,.023704,
.030315,.025634,
.02765,.0275,
-.115,.0275,
-.115,-.0275,
.115,-.0275,
.115,.0275,
.05895,.0275,
0.0*
%
%ADD236MACRO236*%
%ADD197R,.041X.045*%
%AMMACRO177*
21,1,.02,.007,0.0,0.0,141.9*%
%ADD177MACRO177*%
%ADD110C,.15*%
%ADD303R,.013X.039*%
%ADD246R,.063X.024*%
%ADD196R,.063X.06*%
%AMMACRO182*
21,1,.02,.007,0.0,0.0,110.716*%
%ADD182MACRO182*%
%AMMACRO153*
21,1,.02,.007,0.0,0.0,145.6*%
%ADD153MACRO153*%
%ADD120R,.018X.07*%
%ADD66R,.063X.061*%
%ADD322R,.032X.039*%
%ADD268R,.039X.013*%
%ADD245R,.071X.035*%
%ADD238R,.064X.024*%
%AMMACRO229*
21,1,.02,.007,0.0,0.0,134.9*%
%ADD229MACRO229*%
%AMMACRO137*
4,1,21,.0055,-.0095,
.005416,-.010455,
.005168,-.011381,
.004763,-.01225,
.004213,-.013035,
.003535,-.013713,
.00275,-.014263,
.001881,-.014668,
.000955,-.014916,
0.0,-.015,
-.000955,-.014916,
-.001881,-.014668,
-.00275,-.014263,
-.003535,-.013713,
-.004213,-.013035,
-.004763,-.01225,
-.005168,-.011381,
-.005416,-.010455,
-.0055,-.0095,
-.0055,.015,
.0055,.015,
.0055,-.0095,
0.0*
%
%ADD137MACRO137*%
%ADD131R,.07X.018*%
%ADD12R,.061X.063*%
%ADD306R,.037X.016*%
%ADD289R,.055X.08*%
%AMMACRO285*
4,1,21,.004,-.013,
-.004,-.013,
-.004,.009,
-.003939,.009695,
-.003759,.010368,
-.003464,.011,
-.003064,.011571,
-.002571,.012064,
-.002,.012464,
-.001368,.012759,
-.000695,.012939,
0.0,.013,
.000695,.012939,
.001368,.012759,
.002,.012464,
.002571,.012064,
.003064,.011571,
.003464,.011,
.003759,.010368,
.003939,.009695,
.004,.009,
.004,-.013,
0.0*
%
%ADD285MACRO285*%
%ADD260R,.02X.079*%
%AMMACRO168*
21,1,.02,.007,0.0,0.0,161.721*%
%ADD168MACRO168*%
%AMMACRO129*
4,1,21,-.006,-.015,
-.006,.009,
-.005909,.010042,
-.005638,.011052,
-.005196,.012,
-.004596,.012857,
-.003857,.013596,
-.003,.014196,
-.002052,.014638,
-.001042,.014909,
0.0,.015,
.001042,.014909,
.002052,.014638,
.003,.014196,
.003857,.013596,
.004596,.012857,
.005196,.012,
.005638,.011052,
.005909,.010042,
.006,.009,
.006,-.015,
-.006,-.015,
0.0*
%
%ADD129MACRO129*%
%ADD118R,.065X.033*%
%AMMACRO226*
4,1,21,-.015,.006,
.009,.006,
.010042,.005909,
.011052,.005638,
.012,.005196,
.012857,.004596,
.013596,.003857,
.014196,.003,
.014638,.002052,
.014909,.001042,
.015,0.0,
.014909,-.001042,
.014638,-.002052,
.014196,-.003,
.013596,-.003857,
.012857,-.004596,
.012,-.005196,
.011052,-.005638,
.010042,-.005909,
.009,-.006,
-.015,-.006,
-.015,.006,
0.0*
%
%ADD226MACRO226*%
%AMMACRO164*
21,1,.02,.007,0.0,0.0,153.28*%
%ADD164MACRO164*%
%ADD145R,.015X.085*%
%ADD50R,.045X.055*%
%ADD212R,.085X.015*%
%ADD143R,.055X.045*%
%ADD117R,.039X.035*%
%AMMACRO115*
21,1,.035,.039,0.0,0.0,45.*%
%ADD115MACRO115*%
%AMMACRO67*
4,1,21,-.01,-.004,
-.010695,-.003939,
-.011368,-.003759,
-.012,-.003464,
-.012571,-.003064,
-.013064,-.002571,
-.013464,-.002,
-.013759,-.001368,
-.013939,-.000695,
-.014,0.0,
-.013939,.000695,
-.013759,.001368,
-.013464,.002,
-.013064,.002571,
-.012571,.003064,
-.012,.003464,
-.011368,.003759,
-.010695,.003939,
-.01,.004,
.014,.004,
.014,-.004,
-.01,-.004,
0.0*
%
%ADD67MACRO67*%
%AMMACRO37*
4,1,21,-.004,.01,
-.003939,.010695,
-.003759,.011368,
-.003464,.012,
-.003064,.012571,
-.002571,.013064,
-.002,.013464,
-.001368,.013759,
-.000695,.013939,
0.0,.014,
.000695,.013939,
.001368,.013759,
.002,.013464,
.002571,.013064,
.003064,.012571,
.003464,.012,
.003759,.011368,
.003939,.010695,
.004,.01,
.004,-.014,
-.004,-.014,
-.004,.01,
0.0*
%
%ADD37MACRO37*%
%ADD193R,.076X.025*%
%AMMACRO163*
21,1,.02,.007,0.0,0.0,152.58*%
%ADD163MACRO163*%
%AMMACRO158*
21,1,.02,.007,0.0,0.0,125.373*%
%ADD158MACRO158*%
%ADD113R,.035X.039*%
%ADD54R,.14X.14*%
%ADD10C,.363*%
%ADD320O,.094X.048*%
%ADD315R,.075X.045*%
%ADD269R,.072X.057*%
%ADD253R,.047X.055*%
%AMMACRO185*
21,1,.02,.007,0.0,0.0,168.7*%
%ADD185MACRO185*%
%AMMACRO150*
21,1,.02,.007,0.0,0.0,142.195*%
%ADD150MACRO150*%
%ADD230R,.09X.095*%
%AMMACRO161*
21,1,.02,.007,0.0,0.0,125.573*%
%ADD161MACRO161*%
%AMMACRO160*
21,1,.02,.007,0.0,0.0,124.673*%
%ADD160MACRO160*%
%AMMACRO135*
4,1,21,-.0055,.0095,
-.005416,.010455,
-.005168,.011381,
-.004763,.01225,
-.004213,.013035,
-.003535,.013713,
-.00275,.014263,
-.001881,.014668,
-.000955,.014916,
0.0,.015,
.000955,.014916,
.001881,.014668,
.00275,.014263,
.003535,.013713,
.004213,.013035,
.004763,.01225,
.005168,.011381,
.005416,.010455,
.0055,.0095,
.0055,-.015,
-.0055,-.015,
-.0055,.0095,
0.0*
%
%ADD135MACRO135*%
%ADD323R,.059X.028*%
%ADD299O,.098X.046*%
%AMMACRO293*
4,1,21,.006,.0225,
.006,-.0165,
.005909,-.017542,
.005638,-.018552,
.005196,-.0195,
.004596,-.020357,
.003857,-.021096,
.003,-.021696,
.002052,-.022138,
.001042,-.022409,
0.0,-.0225,
-.001042,-.022409,
-.002052,-.022138,
-.003,-.021696,
-.003857,-.021096,
-.004596,-.020357,
-.005196,-.0195,
-.005638,-.018552,
-.005909,-.017542,
-.006,-.0165,
-.006,.0225,
.006,.0225,
0.0*
%
%ADD293MACRO293*%
%ADD275R,.095X.09*%
%ADD239C,.276*%
%AMMACRO155*
21,1,.02,.007,0.0,0.0,124.773*%
%ADD155MACRO155*%
%AMMACRO128*
4,1,21,.006,.015,
.006,-.009,
.005909,-.010042,
.005638,-.011052,
.005196,-.012,
.004596,-.012857,
.003857,-.013596,
.003,-.014196,
.002052,-.014638,
.001042,-.014909,
0.0,-.015,
-.001042,-.014909,
-.002052,-.014638,
-.003,-.014196,
-.003857,-.013596,
-.004596,-.012857,
-.005196,-.012,
-.005638,-.011052,
-.005909,-.010042,
-.006,-.009,
-.006,.015,
.006,.015,
0.0*
%
%ADD128MACRO128*%
%AMMACRO111*
4,1,8,.0585,-.0725,
.0585,.0725,
-.0585,.0725,
-.0585,.04275,
-.0185,.04275,
-.0185,-.04275,
-.0585,-.04275,
-.0585,-.0725,
.0585,-.0725,
0.0*
%
%ADD111MACRO111*%
%ADD43R,.079X.071*%
%AMMACRO234*
4,1,21,.015,-.006,
-.009,-.006,
-.010042,-.005909,
-.011052,-.005638,
-.012,-.005196,
-.012857,-.004596,
-.013596,-.003857,
-.014196,-.003,
-.014638,-.002052,
-.014909,-.001042,
-.015,0.0,
-.014909,.001042,
-.014638,.002052,
-.014196,.003,
-.013596,.003857,
-.012857,.004596,
-.012,.005196,
-.011052,.005638,
-.010042,.005909,
-.009,.006,
.015,.006,
.015,-.006,
0.0*
%
%ADD234MACRO234*%
%ADD222R,.071X.079*%
%AMMACRO181*
21,1,.02,.007,0.0,0.0,157.651*%
%ADD181MACRO181*%
%AMMACRO159*
21,1,.02,.007,0.0,0.0,125.386*%
%ADD159MACRO159*%
%AMMACRO156*
21,1,.02,.007,0.0,0.0,124.873*%
%ADD156MACRO156*%
%AMMACRO134*
4,1,21,-.0095,-.0055,
-.010455,-.005416,
-.011381,-.005168,
-.01225,-.004763,
-.013035,-.004213,
-.013713,-.003535,
-.014263,-.00275,
-.014668,-.001881,
-.014916,-.000955,
-.015,0.0,
-.014916,.000955,
-.014668,.001881,
-.014263,.00275,
-.013713,.003535,
-.013035,.004213,
-.01225,.004763,
-.011381,.005168,
-.010455,.005416,
-.0095,.0055,
.015,.0055,
.015,-.0055,
-.0095,-.0055,
0.0*
%
%ADD134MACRO134*%
%AMMACRO255*
21,1,.02,.007,0.0,0.0,134.828*%
%ADD255MACRO255*%
%AMMACRO188*
21,1,.02,.007,0.0,0.0,179.9*%
%ADD188MACRO188*%
%AMMACRO157*
21,1,.02,.007,0.0,0.0,124.973*%
%ADD157MACRO157*%
%AMMACRO154*
21,1,.02,.007,0.0,0.0,125.486*%
%ADD154MACRO154*%
%ADD146R,.063X.089*%
%AMMACRO127*
4,1,21,-.015,.006,
.009,.006,
.010042,.005909,
.011052,.005638,
.012,.005196,
.012857,.004596,
.013596,.003857,
.014196,.003,
.014638,.002052,
.014909,.001042,
.015,0.0,
.014909,-.001042,
.014638,-.002052,
.014196,-.003,
.013596,-.003857,
.012857,-.004596,
.012,-.005196,
.011052,-.005638,
.010042,-.005909,
.009,-.006,
-.015,-.006,
-.015,.006,
0.0*
%
%ADD127MACRO127*%
%AMMACRO227*
4,1,21,.006,.015,
.006,-.009,
.005909,-.010042,
.005638,-.011052,
.005196,-.012,
.004596,-.012857,
.003857,-.013596,
.003,-.014196,
.002052,-.014638,
.001042,-.014909,
0.0,-.015,
-.001042,-.014909,
-.002052,-.014638,
-.003,-.014196,
-.003857,-.013596,
-.004596,-.012857,
-.005196,-.012,
-.005638,-.011052,
-.005909,-.010042,
-.006,-.009,
-.006,.015,
.006,.015,
0.0*
%
%ADD227MACRO227*%
%AMMACRO162*
21,1,.02,.007,0.0,0.0,157.851*%
%ADD162MACRO162*%
%ADD103R,.089X.063*%
%ADD51R,.079X.092*%
%AMMACRO284*
4,1,21,-.013,-.004,
-.013,.004,
.009,.004,
.009695,.003939,
.010368,.003759,
.011,.003464,
.011571,.003064,
.012064,.002571,
.012464,.002,
.012759,.001368,
.012939,.000695,
.013,0.0,
.012939,-.000695,
.012759,-.001368,
.012464,-.002,
.012064,-.002571,
.011571,-.003064,
.011,-.003464,
.010368,-.003759,
.009695,-.003939,
.009,-.004,
-.013,-.004,
0.0*
%
%ADD284MACRO284*%
%ADD235R,.049X.068*%
%ADD221R,.092X.079*%
%AMMACRO199*
21,1,.02,.007,0.0,0.0,164.882*%
%ADD199MACRO199*%
%AMMACRO294*
4,1,21,-.006,-.0225,
-.006,.0165,
-.005909,.017542,
-.005638,.018552,
-.005196,.0195,
-.004596,.020357,
-.003857,.021096,
-.003,.021696,
-.002052,.022138,
-.001042,.022409,
0.0,.0225,
.001042,.022409,
.002052,.022138,
.003,.021696,
.003857,.021096,
.004596,.020357,
.005196,.0195,
.005638,.018552,
.005909,.017542,
.006,.0165,
.006,-.0225,
-.006,-.0225,
0.0*
%
%ADD294MACRO294*%
%AMMACRO68*
4,1,21,-.004,.01,
-.003939,.010695,
-.003759,.011368,
-.003464,.012,
-.003064,.012571,
-.002571,.013064,
-.002,.013464,
-.001368,.013759,
-.000695,.013939,
0.0,.014,
.000695,.013939,
.001368,.013759,
.002,.013464,
.002571,.013064,
.003064,.012571,
.003464,.012,
.003759,.011368,
.003939,.010695,
.004,.01,
.004,-.014,
-.004,-.014,
-.004,.01,
0.0*
%
%ADD68MACRO68*%
%AMMACRO38*
4,1,21,.01,.004,
.010695,.003939,
.011368,.003759,
.012,.003464,
.012571,.003064,
.013064,.002571,
.013464,.002,
.013759,.001368,
.013939,.000695,
.014,0.0,
.013939,-.000695,
.013759,-.001368,
.013464,-.002,
.013064,-.002571,
.012571,-.003064,
.012,-.003464,
.011368,-.003759,
.010695,-.003939,
.01,-.004,
-.014,-.004,
-.014,.004,
.01,.004,
0.0*
%
%ADD38MACRO38*%
%AMMACRO291*
4,1,21,.0225,-.006,
-.0165,-.006,
-.017542,-.005909,
-.018552,-.005638,
-.0195,-.005196,
-.020357,-.004596,
-.021096,-.003857,
-.021696,-.003,
-.022138,-.002052,
-.022409,-.001042,
-.0225,0.0,
-.022409,.001042,
-.022138,.002052,
-.021696,.003,
-.021096,.003857,
-.020357,.004596,
-.0195,.005196,
-.018552,.005638,
-.017542,.005909,
-.0165,.006,
.0225,.006,
.0225,-.006,
0.0*
%
%ADD291MACRO291*%
%AMMACRO138*
4,1,40,-.007,-.011,
.007,-.011,
.007695,-.010939,
.008368,-.010759,
.009,-.010464,
.009571,-.010064,
.010064,-.009571,
.010464,-.009,
.010759,-.008368,
.010939,-.007695,
.011,-.007,
.011,.007,
.010939,.007695,
.010759,.008368,
.010464,.009,
.010064,.009571,
.009571,.010064,
.009,.010464,
.008368,.010759,
.007695,.010939,
.007,.011,
-.007,.011,
-.007695,.010939,
-.008368,.010759,
-.009,.010464,
-.009571,.010064,
-.010064,.009571,
-.010464,.009,
-.010759,.008368,
-.010939,.007695,
-.011,.007,
-.011,-.007,
-.010939,-.007695,
-.010759,-.008368,
-.010464,-.009,
-.010064,-.009571,
-.009571,-.010064,
-.009,-.010464,
-.008368,-.010759,
-.007695,-.010939,
-.007,-.011,
0.0*
%
%ADD138MACRO138*%
%AMMACRO91*
4,1,40,-.008,-.012,
.008,-.012,
.008695,-.011939,
.009368,-.011759,
.01,-.011464,
.010571,-.011064,
.011064,-.010571,
.011464,-.01,
.011759,-.009368,
.011939,-.008695,
.012,-.008,
.012,.008,
.011939,.008695,
.011759,.009368,
.011464,.01,
.011064,.010571,
.010571,.011064,
.01,.011464,
.009368,.011759,
.008695,.011939,
.008,.012,
-.008,.012,
-.008695,.011939,
-.009368,.011759,
-.01,.011464,
-.010571,.011064,
-.011064,.010571,
-.011464,.01,
-.011759,.009368,
-.011939,.008695,
-.012,.008,
-.012,-.008,
-.011939,-.008695,
-.011759,-.009368,
-.011464,-.01,
-.011064,-.010571,
-.010571,-.011064,
-.01,-.011464,
-.009368,-.011759,
-.008695,-.011939,
-.008,-.012,
0.0*
%
%ADD91MACRO91*%
%AMMACRO33*
4,1,40,.012,-.008,
.012,.008,
.011939,.008695,
.011759,.009368,
.011464,.01,
.011064,.010571,
.010571,.011064,
.01,.011464,
.009368,.011759,
.008695,.011939,
.008,.012,
-.008,.012,
-.008695,.011939,
-.009368,.011759,
-.01,.011464,
-.010571,.011064,
-.011064,.010571,
-.011464,.01,
-.011759,.009368,
-.011939,.008695,
-.012,.008,
-.012,-.008,
-.011939,-.008695,
-.011759,-.009368,
-.011464,-.01,
-.011064,-.010571,
-.010571,-.011064,
-.01,-.011464,
-.009368,-.011759,
-.008695,-.011939,
-.008,-.012,
.008,-.012,
.008695,-.011939,
.009368,-.011759,
.01,-.011464,
.010571,-.011064,
.011064,-.010571,
.011464,-.01,
.011759,-.009368,
.011939,-.008695,
.012,-.008,
0.0*
%
%ADD33MACRO33*%
%AMMACRO64*
4,1,40,-.011,.007,
-.011,-.007,
-.010939,-.007695,
-.010759,-.008368,
-.010464,-.009,
-.010064,-.009571,
-.009571,-.010064,
-.009,-.010464,
-.008368,-.010759,
-.007695,-.010939,
-.007,-.011,
.007,-.011,
.007695,-.010939,
.008368,-.010759,
.009,-.010464,
.009571,-.010064,
.010064,-.009571,
.010464,-.009,
.010759,-.008368,
.010939,-.007695,
.011,-.007,
.011,.007,
.010939,.007695,
.010759,.008368,
.010464,.009,
.010064,.009571,
.009571,.010064,
.009,.010464,
.008368,.010759,
.007695,.010939,
.007,.011,
-.007,.011,
-.007695,.010939,
-.008368,.010759,
-.009,.010464,
-.009571,.010064,
-.010064,.009571,
-.010464,.009,
-.010759,.008368,
-.010939,.007695,
-.011,.007,
0.0*
%
%ADD64MACRO64*%
%AMMACRO283*
4,1,21,.013,.004,
.013,-.004,
-.009,-.004,
-.009695,-.003939,
-.010368,-.003759,
-.011,-.003464,
-.011571,-.003064,
-.012064,-.002571,
-.012464,-.002,
-.012759,-.001368,
-.012939,-.000695,
-.013,0.0,
-.012939,.000695,
-.012759,.001368,
-.012464,.002,
-.012064,.002571,
-.011571,.003064,
-.011,.003464,
-.010368,.003759,
-.009695,.003939,
-.009,.004,
.013,.004,
0.0*
%
%ADD283MACRO283*%
%AMMACRO207*
4,1,40,.017,-.013,
.017,.013,
.016939,.013695,
.016759,.014368,
.016464,.015,
.016064,.015571,
.015571,.016064,
.015,.016464,
.014368,.016759,
.013695,.016939,
.013,.017,
-.013,.017,
-.013695,.016939,
-.014368,.016759,
-.015,.016464,
-.015571,.016064,
-.016064,.015571,
-.016464,.015,
-.016759,.014368,
-.016939,.013695,
-.017,.013,
-.017,-.013,
-.016939,-.013695,
-.016759,-.014368,
-.016464,-.015,
-.016064,-.015571,
-.015571,-.016064,
-.015,-.016464,
-.014368,-.016759,
-.013695,-.016939,
-.013,-.017,
.013,-.017,
.013695,-.016939,
.014368,-.016759,
.015,-.016464,
.015571,-.016064,
.016064,-.015571,
.016464,-.015,
.016759,-.014368,
.016939,-.013695,
.017,-.013,
0.0*
%
%ADD207MACRO207*%
%AMMACRO35*
4,1,40,.013,.017,
-.013,.017,
-.013695,.016939,
-.014368,.016759,
-.015,.016464,
-.015571,.016064,
-.016064,.015571,
-.016464,.015,
-.016759,.014368,
-.016939,.013695,
-.017,.013,
-.017,-.013,
-.016939,-.013695,
-.016759,-.014368,
-.016464,-.015,
-.016064,-.015571,
-.015571,-.016064,
-.015,-.016464,
-.014368,-.016759,
-.013695,-.016939,
-.013,-.017,
.013,-.017,
.013695,-.016939,
.014368,-.016759,
.015,-.016464,
.015571,-.016064,
.016064,-.015571,
.016464,-.015,
.016759,-.014368,
.016939,-.013695,
.017,-.013,
.017,.013,
.016939,.013695,
.016759,.014368,
.016464,.015,
.016064,.015571,
.015571,.016064,
.015,.016464,
.014368,.016759,
.013695,.016939,
.013,.017,
0.0*
%
%ADD35MACRO35*%
%AMMACRO233*
21,1,.02,.007,0.0,0.0,179.828*%
%ADD233MACRO233*%
%AMMACRO200*
21,1,.02,.007,0.0,0.0,164.879*%
%ADD200MACRO200*%
%AMMACRO282*
4,1,21,-.004,.013,
.004,.013,
.004,-.009,
.003939,-.009695,
.003759,-.010368,
.003464,-.011,
.003064,-.011571,
.002571,-.012064,
.002,-.012464,
.001368,-.012759,
.000695,-.012939,
0.0,-.013,
-.000695,-.012939,
-.001368,-.012759,
-.002,-.012464,
-.002571,-.012064,
-.003064,-.011571,
-.003464,-.011,
-.003759,-.010368,
-.003939,-.009695,
-.004,-.009,
-.004,.013,
0.0*
%
%ADD282MACRO282*%
%AMMACRO76*
4,1,21,-.01,-.004,
-.010695,-.003939,
-.011368,-.003759,
-.012,-.003464,
-.012571,-.003064,
-.013064,-.002571,
-.013464,-.002,
-.013759,-.001368,
-.013939,-.000695,
-.014,0.0,
-.013939,.000695,
-.013759,.001368,
-.013464,.002,
-.013064,.002571,
-.012571,.003064,
-.012,.003464,
-.011368,.003759,
-.010695,.003939,
-.01,.004,
.014,.004,
.014,-.004,
-.01,-.004,
0.0*
%
%ADD76MACRO76*%
%AMMACRO70*
4,1,21,.004,-.01,
.003939,-.010695,
.003759,-.011368,
.003464,-.012,
.003064,-.012571,
.002571,-.013064,
.002,-.013464,
.001368,-.013759,
.000695,-.013939,
0.0,-.014,
-.000695,-.013939,
-.001368,-.013759,
-.002,-.013464,
-.002571,-.013064,
-.003064,-.012571,
-.003464,-.012,
-.003759,-.011368,
-.003939,-.010695,
-.004,-.01,
-.004,.014,
.004,.014,
.004,-.01,
0.0*
%
%ADD70MACRO70*%
%AMMACRO251*
21,1,.02,.007,0.0,0.0,179.695*%
%ADD251MACRO251*%
%AMMACRO69*
4,1,21,.01,.004,
.010695,.003939,
.011368,.003759,
.012,.003464,
.012571,.003064,
.013064,.002571,
.013464,.002,
.013759,.001368,
.013939,.000695,
.014,0.0,
.013939,-.000695,
.013759,-.001368,
.013464,-.002,
.013064,-.002571,
.012571,-.003064,
.012,-.003464,
.011368,-.003759,
.010695,-.003939,
.01,-.004,
-.014,-.004,
-.014,.004,
.01,.004,
0.0*
%
%ADD69MACRO69*%
%AMMACRO39*
4,1,21,.004,-.01,
.003939,-.010695,
.003759,-.011368,
.003464,-.012,
.003064,-.012571,
.002571,-.013064,
.002,-.013464,
.001368,-.013759,
.000695,-.013939,
0.0,-.014,
-.000695,-.013939,
-.001368,-.013759,
-.002,-.013464,
-.002571,-.013064,
-.003064,-.012571,
-.003464,-.012,
-.003759,-.011368,
-.003939,-.010695,
-.004,-.01,
-.004,.014,
.004,.014,
.004,-.01,
0.0*
%
%ADD39MACRO39*%
%AMMACRO139*
4,1,40,-.007,-.011,
.007,-.011,
.007695,-.010939,
.008368,-.010759,
.009,-.010464,
.009571,-.010064,
.010064,-.009571,
.010464,-.009,
.010759,-.008368,
.010939,-.007695,
.011,-.007,
.011,.007,
.010939,.007695,
.010759,.008368,
.010464,.009,
.010064,.009571,
.009571,.010064,
.009,.010464,
.008368,.010759,
.007695,.010939,
.007,.011,
-.007,.011,
-.007695,.010939,
-.008368,.010759,
-.009,.010464,
-.009571,.010064,
-.010064,.009571,
-.010464,.009,
-.010759,.008368,
-.010939,.007695,
-.011,.007,
-.011,-.007,
-.010939,-.007695,
-.010759,-.008368,
-.010464,-.009,
-.010064,-.009571,
-.009571,-.010064,
-.009,-.010464,
-.008368,-.010759,
-.007695,-.010939,
-.007,-.011,
0.0*
%
%ADD139MACRO139*%
%AMMACRO92*
4,1,40,-.008,-.012,
.008,-.012,
.008695,-.011939,
.009368,-.011759,
.01,-.011464,
.010571,-.011064,
.011064,-.010571,
.011464,-.01,
.011759,-.009368,
.011939,-.008695,
.012,-.008,
.012,.008,
.011939,.008695,
.011759,.009368,
.011464,.01,
.011064,.010571,
.010571,.011064,
.01,.011464,
.009368,.011759,
.008695,.011939,
.008,.012,
-.008,.012,
-.008695,.011939,
-.009368,.011759,
-.01,.011464,
-.010571,.011064,
-.011064,.010571,
-.011464,.01,
-.011759,.009368,
-.011939,.008695,
-.012,.008,
-.012,-.008,
-.011939,-.008695,
-.011759,-.009368,
-.011464,-.01,
-.011064,-.010571,
-.010571,-.011064,
-.01,-.011464,
-.009368,-.011759,
-.008695,-.011939,
-.008,-.012,
0.0*
%
%ADD92MACRO92*%
%AMMACRO34*
4,1,40,.012,-.008,
.012,.008,
.011939,.008695,
.011759,.009368,
.011464,.01,
.011064,.010571,
.010571,.011064,
.01,.011464,
.009368,.011759,
.008695,.011939,
.008,.012,
-.008,.012,
-.008695,.011939,
-.009368,.011759,
-.01,.011464,
-.010571,.011064,
-.011064,.010571,
-.011464,.01,
-.011759,.009368,
-.011939,.008695,
-.012,.008,
-.012,-.008,
-.011939,-.008695,
-.011759,-.009368,
-.011464,-.01,
-.011064,-.010571,
-.010571,-.011064,
-.01,-.011464,
-.009368,-.011759,
-.008695,-.011939,
-.008,-.012,
.008,-.012,
.008695,-.011939,
.009368,-.011759,
.01,-.011464,
.010571,-.011064,
.011064,-.010571,
.011464,-.01,
.011759,-.009368,
.011939,-.008695,
.012,-.008,
0.0*
%
%ADD34MACRO34*%
%AMMACRO65*
4,1,40,-.011,.007,
-.011,-.007,
-.010939,-.007695,
-.010759,-.008368,
-.010464,-.009,
-.010064,-.009571,
-.009571,-.010064,
-.009,-.010464,
-.008368,-.010759,
-.007695,-.010939,
-.007,-.011,
.007,-.011,
.007695,-.010939,
.008368,-.010759,
.009,-.010464,
.009571,-.010064,
.010064,-.009571,
.010464,-.009,
.010759,-.008368,
.010939,-.007695,
.011,-.007,
.011,.007,
.010939,.007695,
.010759,.008368,
.010464,.009,
.010064,.009571,
.009571,.010064,
.009,.010464,
.008368,.010759,
.007695,.010939,
.007,.011,
-.007,.011,
-.007695,.010939,
-.008368,.010759,
-.009,.010464,
-.009571,.010064,
-.010064,.009571,
-.010464,.009,
-.010759,.008368,
-.010939,.007695,
-.011,.007,
0.0*
%
%ADD65MACRO65*%
%ADD326C,.006*%
G75*
%LPD*%
G75*
G36*
G01X46750Y-8225D02*
Y6275D01*
X32250D01*
Y-8225D01*
X46750D01*
G37*
G36*
G01X15350Y511050D02*
X850D01*
Y496550D01*
X15350D01*
Y511050D01*
G37*
G36*
G01X78000Y304500D02*
X65000D01*
Y291500D01*
X78000D01*
Y304500D01*
G37*
G36*
G01X69400Y371100D02*
Y356900D01*
X83600D01*
Y371100D01*
X69400D01*
G37*
G36*
G01X673350Y270250D02*
X658850D01*
Y255750D01*
X673350D01*
Y270250D01*
G37*
G36*
G01X654719Y306448D02*
X679319D01*
Y331048D01*
X654719D01*
Y306448D01*
G37*
G36*
G01X726100Y8300D02*
X715900D01*
Y1700D01*
X726100D01*
Y8300D01*
G37*
G36*
G01X674348Y11337D02*
Y21537D01*
X667748D01*
Y11337D01*
X674348D01*
G37*
G36*
G01X708150Y51750D02*
X690850D01*
Y61150D01*
X708150D01*
Y51750D01*
G37*
G36*
G01X700250Y43850D02*
X708150D01*
Y49750D01*
X700250D01*
Y43850D01*
G37*
G36*
G01X690850D02*
X698750D01*
Y49750D01*
X690850D01*
Y43850D01*
G37*
G36*
G01X718400Y282100D02*
Y267900D01*
X732600D01*
Y282100D01*
X718400D01*
G37*
G36*
G01X714943Y586402D02*
X725143D01*
Y593002D01*
X714943D01*
Y586402D01*
G37*
G36*
G01X674747Y575330D02*
Y585530D01*
X668147D01*
Y575330D01*
X674747D01*
G37*
G36*
G01X708150Y538000D02*
X690850D01*
Y547400D01*
X708150D01*
Y538000D01*
G37*
G36*
G01X700250Y530100D02*
X708150D01*
Y536000D01*
X700250D01*
Y530100D01*
G37*
G36*
G01X690850D02*
X698750D01*
Y536000D01*
X690850D01*
Y530100D01*
G37*
G36*
G01X1364250Y67750D02*
X1349750D01*
Y53250D01*
X1364250D01*
Y67750D01*
G37*
G36*
G01X1368350Y111700D02*
X1351050D01*
Y121100D01*
X1368350D01*
Y111700D01*
G37*
G36*
G01X1360450Y103800D02*
X1368350D01*
Y109700D01*
X1360450D01*
Y103800D01*
G37*
G36*
G01X1351050D02*
X1358950D01*
Y109700D01*
X1351050D01*
Y103800D01*
G37*
G36*
G01X1363150Y522300D02*
X1345850D01*
Y531700D01*
X1363150D01*
Y522300D01*
G37*
G36*
G01X1355250Y514400D02*
X1363150D01*
Y520300D01*
X1355250D01*
Y514400D01*
G37*
G36*
G01X1345850D02*
X1353750D01*
Y520300D01*
X1345850D01*
Y514400D01*
G37*
G36*
G01X1407310Y536705D02*
X1421810D01*
Y551205D01*
X1407310D01*
Y536705D01*
G37*
G36*
G01X1585900Y3000D02*
Y-4200D01*
X1593100D01*
Y3000D01*
X1585900D01*
G37*
G36*
G01X1539950Y262450D02*
Y270550D01*
X1542500D01*
Y274900D01*
X1543250D01*
Y272000D01*
X1544750D01*
Y274900D01*
X1545500D01*
Y270550D01*
X1548050D01*
Y262450D01*
X1545500D01*
Y258100D01*
X1544750D01*
Y261000D01*
X1543250D01*
Y258100D01*
X1542500D01*
Y262450D01*
X1539950D01*
G37*
G36*
G01X1580541Y584748D02*
X1590741D01*
Y591348D01*
X1580541D01*
Y584748D01*
G37*
G36*
G01X1550950Y598250D02*
X1565450D01*
Y612750D01*
X1550950D01*
Y598250D01*
G37*
G36*
G01X1628453Y347196D02*
X1636553D01*
Y339096D01*
X1628453D01*
Y347196D01*
G37*
G36*
G01X1708428Y514650D02*
Y511150D01*
X1714728D01*
Y514650D01*
X1708428D01*
G37*
G36*
G01X1715996Y491260D02*
Y500260D01*
X1706096D01*
Y498960D01*
X1709196D01*
Y497693D01*
X1706096D01*
Y496393D01*
X1709196D01*
Y495127D01*
X1706096D01*
Y493827D01*
X1709196D01*
Y492560D01*
X1706096D01*
Y491260D01*
X1715996D01*
G37*
G36*
G01X1733743Y591142D02*
Y598342D01*
X1726543D01*
Y591142D01*
X1733743D01*
G37*
G36*
G01X1784900Y94100D02*
Y83900D01*
X1791500D01*
Y94100D01*
X1784900D01*
G37*
G36*
G01X1815200Y164600D02*
Y154400D01*
X1821800D01*
Y164600D01*
X1815200D01*
G37*
G36*
G01X1873450Y113450D02*
X1889550D01*
Y129550D01*
X1873450D01*
Y113450D01*
G37*
G36*
G01X1845600Y152700D02*
X1855800D01*
Y159300D01*
X1845600D01*
Y152700D01*
G37*
G36*
G01X1935009Y84406D02*
X1944009D01*
Y94306D01*
X1942709D01*
Y91206D01*
X1941442D01*
Y94306D01*
X1940142D01*
Y91206D01*
X1938876D01*
Y94306D01*
X1937576D01*
Y91206D01*
X1936309D01*
Y94306D01*
X1935009D01*
Y84406D01*
G37*
G36*
G01X1913600Y180200D02*
X1899400D01*
Y166000D01*
X1913600D01*
Y180200D01*
G37*
G36*
G01X1840500Y89000D02*
Y92500D01*
X1844000D01*
Y89000D01*
X1840500D01*
G37*
G36*
G01X1957726Y98446D02*
Y104746D01*
X1961226D01*
Y98446D01*
X1957726D01*
G37*
G54D100*
X85161Y352600D03*
X83587D03*
X82012D03*
X80437D03*
X78862D03*
X77287D03*
X75713D03*
X74138D03*
X72563D03*
X70988D03*
X69413D03*
X67839D03*
X724713Y263600D03*
X723138D03*
X721563D03*
X719988D03*
X718413D03*
X716839D03*
X734161D03*
X732587D03*
X731012D03*
X729437D03*
X727862D03*
X726287D03*
G54D200*
X1417111Y466941D03*
G54D110*
X224410Y301378D03*
X326772Y163582D03*
Y439173D03*
X500000Y163582D03*
Y439173D03*
X602362Y214764D03*
Y387992D03*
X874016Y301378D03*
X976378Y163582D03*
Y439173D03*
X1149606Y163582D03*
Y439173D03*
X1251969Y214764D03*
Y387992D03*
G54D101*
X65100Y355339D03*
Y356913D03*
Y358488D03*
Y360063D03*
Y361638D03*
Y363213D03*
Y364787D03*
Y366362D03*
Y367937D03*
Y369512D03*
Y371087D03*
Y372661D03*
X714100Y266339D03*
Y267913D03*
Y269488D03*
Y271063D03*
Y272638D03*
Y274213D03*
Y275787D03*
Y277362D03*
Y278937D03*
Y280512D03*
Y282087D03*
Y283661D03*
G54D111*
X210427Y649635D03*
X398011Y649515D03*
X585479Y649245D03*
X901122Y649224D03*
X1214648Y649213D03*
X1528146Y649243D03*
G54D120*
X657250Y-14930D03*
Y3070D03*
X652130Y-14930D03*
Y3070D03*
X654690Y-14930D03*
Y3070D03*
X649570Y-14930D03*
Y3070D03*
X1274050Y109670D03*
Y127670D03*
X1268930Y109670D03*
Y127670D03*
X1271490Y109670D03*
Y127670D03*
X1266370Y109670D03*
Y127670D03*
G54D210*
X1507076Y93586D03*
Y91618D03*
Y89649D03*
Y87681D03*
Y85712D03*
Y83744D03*
Y154610D03*
Y152641D03*
Y150673D03*
Y148704D03*
Y138862D03*
Y136893D03*
Y134925D03*
Y132956D03*
Y130988D03*
Y129019D03*
Y127051D03*
Y125082D03*
Y123114D03*
Y121145D03*
Y119177D03*
Y117208D03*
Y115240D03*
Y113271D03*
Y111303D03*
Y109334D03*
Y107366D03*
Y105397D03*
Y103429D03*
Y101460D03*
Y99492D03*
Y97523D03*
Y95555D03*
Y156578D03*
X1536801Y94570D03*
Y92602D03*
Y90633D03*
Y88665D03*
Y86696D03*
Y84728D03*
Y155594D03*
Y153626D03*
Y151657D03*
Y149689D03*
Y139846D03*
Y137878D03*
Y135909D03*
Y133941D03*
Y131972D03*
Y130004D03*
Y128035D03*
Y126067D03*
Y124098D03*
Y122130D03*
Y120161D03*
Y118192D03*
Y116224D03*
Y114255D03*
Y112287D03*
Y110318D03*
Y108350D03*
Y106381D03*
Y104413D03*
Y102444D03*
Y100476D03*
Y98507D03*
Y96539D03*
G54D300*
X1851250Y561000D03*
G54D201*
X1430584Y467544D03*
G54D102*
X53839Y427982D03*
X64839Y435856D03*
X53839Y443730D03*
G54D103*
X103191Y452592D03*
Y471458D03*
G54D10*
X0Y0D03*
G54D121*
X655500Y57400D03*
X655600Y543750D03*
X677000Y57400D03*
X677100Y543750D03*
X1314300Y116800D03*
X1335800D03*
X1308150Y529500D03*
X1329650D03*
X1589980Y270040D03*
X1568480D03*
G54D220*
X1475723Y602756D03*
X1511261Y604024D03*
G54D310*
X1953740Y217834D03*
Y215866D03*
Y213897D03*
Y233582D03*
Y231614D03*
Y225708D03*
Y223740D03*
X1960433Y217834D03*
Y215866D03*
Y233582D03*
Y231614D03*
Y229645D03*
Y227677D03*
Y225708D03*
Y223740D03*
Y221771D03*
Y219803D03*
G54D130*
X666327Y387100D03*
Y415100D03*
X1317000Y72800D03*
Y44800D03*
X1295200Y133050D03*
Y105050D03*
X1454600Y584100D03*
Y556100D03*
G54D301*
X1952756Y-14760D03*
Y58068D03*
G54D211*
X1527844Y159531D03*
G54D112*
X270109Y216909D03*
X276869D03*
X283629D03*
X290389D03*
X266729Y214960D03*
X273489D03*
X280249D03*
X287009D03*
X270109Y213009D03*
X276869D03*
X283629D03*
X290389D03*
X266729Y211060D03*
X273489D03*
X280249D03*
X287009D03*
X270109Y209109D03*
X276869D03*
X283629D03*
X290389D03*
X273489Y207159D03*
X280249D03*
X287009D03*
X276869Y205210D03*
X283629D03*
X290389D03*
X273489Y203260D03*
X280249D03*
X287009D03*
X276869Y201309D03*
X283629D03*
X290389D03*
X280249Y199360D03*
X287009D03*
X283629Y197409D03*
X290389D03*
X270109Y232509D03*
X276869D03*
X283629D03*
X290389D03*
X266729Y230559D03*
X273489D03*
X280249D03*
X287009D03*
X270109Y228610D03*
X276869D03*
X283629D03*
X290389D03*
X266729Y226660D03*
X273489D03*
X280249D03*
X287009D03*
X270109Y224709D03*
X276869D03*
X283629D03*
X290389D03*
X270109Y220809D03*
X276869D03*
X283629D03*
X290389D03*
X266729Y218860D03*
X273489D03*
X280249D03*
X287009D03*
X270109Y279310D03*
X276869D03*
X283629D03*
X290389D03*
X273489Y277360D03*
X280249D03*
X287009D03*
X270109Y275409D03*
X276869D03*
X283629D03*
X290389D03*
X266729Y273460D03*
X273489D03*
X280249D03*
X287009D03*
X270109Y271509D03*
X276869D03*
X283629D03*
X290389D03*
X266729Y269560D03*
X273489D03*
X280249D03*
X287009D03*
X270109Y267609D03*
X276869D03*
X283629D03*
X290389D03*
X266729Y265660D03*
X273489D03*
X280249D03*
X287009D03*
X270109Y263709D03*
X276869D03*
X283629D03*
X290389D03*
X266729Y261760D03*
X273489D03*
X280249D03*
X287009D03*
X270109Y259809D03*
X276869D03*
X283629D03*
X290389D03*
X266729Y257860D03*
X273489D03*
X280249D03*
X287009D03*
X270109Y255909D03*
X276869D03*
X283629D03*
X290389D03*
X266729Y253960D03*
X273489D03*
X280249D03*
X287009D03*
X270109Y252009D03*
X276869D03*
X283629D03*
X290389D03*
X266729Y250060D03*
X273489D03*
X280249D03*
X287009D03*
X270109Y248109D03*
X276869D03*
X283629D03*
X290389D03*
X266729Y246160D03*
X273489D03*
X280249D03*
X287009D03*
X270109Y244209D03*
X276869D03*
X283629D03*
X290389D03*
X266729Y242260D03*
X273489D03*
X280249D03*
X287009D03*
X270109Y240309D03*
X276869D03*
X283629D03*
X290389D03*
X266729Y238360D03*
X273489D03*
X280249D03*
X287009D03*
X270109Y236409D03*
X276869D03*
X283629D03*
X290389D03*
X266729Y234460D03*
X273489D03*
X280249D03*
X287009D03*
X266729Y222760D03*
X273489D03*
X280249D03*
X287009D03*
X270109Y341709D03*
X276869D03*
X283629D03*
X290389D03*
X266729Y339760D03*
X273489D03*
X280249D03*
X287009D03*
X270109Y337809D03*
X276869D03*
X283629D03*
X290389D03*
X266729Y335860D03*
X273489D03*
X280249D03*
X287009D03*
X270109Y333909D03*
X276869D03*
X283629D03*
X290389D03*
X266729Y331960D03*
X273489D03*
X280249D03*
X287009D03*
X270109Y330009D03*
X276869D03*
X283629D03*
X290389D03*
X266729Y328060D03*
X273489D03*
X280249D03*
X287009D03*
X270109Y326110D03*
X276869D03*
X283629D03*
X290389D03*
X273489Y324160D03*
X280249D03*
X287009D03*
X270109Y322209D03*
X276869D03*
X283629D03*
X290389D03*
X273489Y320260D03*
X280249D03*
X287009D03*
X270109Y318309D03*
X276869D03*
X283629D03*
X290389D03*
X273489Y316360D03*
X280249D03*
X287009D03*
X276869Y314409D03*
X283629D03*
X290389D03*
X273489Y312460D03*
X280249D03*
X287009D03*
X276869Y310509D03*
X283629D03*
X290389D03*
X273489Y308560D03*
X280249D03*
X287009D03*
X276869Y306609D03*
X283629D03*
X290389D03*
X273489Y304660D03*
X280249D03*
X287009D03*
X276869Y302709D03*
X283629D03*
X290389D03*
X273489Y300760D03*
X280249D03*
X287009D03*
X276869Y298809D03*
X283629D03*
X290389D03*
X273489Y296860D03*
X280249D03*
X287009D03*
X276869Y294909D03*
X283629D03*
X290389D03*
X273489Y292959D03*
X280249D03*
X287009D03*
X276869Y291009D03*
X283629D03*
X290389D03*
X273489Y289060D03*
X280249D03*
X287009D03*
X276869Y287109D03*
X283629D03*
X290389D03*
X273489Y285160D03*
X280249D03*
X287009D03*
X270109Y283209D03*
X276869D03*
X283629D03*
X290389D03*
X273489Y281260D03*
X280249D03*
X287009D03*
X276869Y400209D03*
X283629D03*
X290389D03*
X273489Y398260D03*
X280249D03*
X287009D03*
X276869Y396309D03*
X283629D03*
X290389D03*
X273489Y394359D03*
X280249D03*
X287009D03*
X270109Y392410D03*
X276869D03*
X283629D03*
X290389D03*
X273489Y390460D03*
X280249D03*
X287009D03*
X270109Y388509D03*
X276869D03*
X283629D03*
X290389D03*
X273489Y386560D03*
X280249D03*
X287009D03*
X270109Y384609D03*
X276869D03*
X283629D03*
X290389D03*
X273489Y382660D03*
X280249D03*
X287009D03*
X270109Y380709D03*
X276869D03*
X283629D03*
X290389D03*
X273489Y378760D03*
X280249D03*
X287009D03*
X270109Y376809D03*
X276869D03*
X283629D03*
X290389D03*
X273489Y374860D03*
X280249D03*
X287009D03*
X273489Y370959D03*
X280249D03*
X287009D03*
X270109Y369010D03*
X276869D03*
X283629D03*
X290389D03*
X273489Y367060D03*
X280249D03*
X287009D03*
X270109Y365109D03*
X276869D03*
X283629D03*
X290389D03*
X273489Y363160D03*
X280249D03*
X287009D03*
X270109Y361209D03*
X276869D03*
X283629D03*
X290389D03*
X273489Y359260D03*
X280249D03*
X287009D03*
X270109Y357309D03*
X276869D03*
X283629D03*
X290389D03*
X266729Y355360D03*
X273489D03*
X280249D03*
X287009D03*
X270109Y353409D03*
X276869D03*
X283629D03*
X290389D03*
X266729Y351460D03*
X273489D03*
X280249D03*
X287009D03*
X270109Y349509D03*
X276869D03*
X283629D03*
X290389D03*
X266729Y347560D03*
X273489D03*
X280249D03*
X287009D03*
X270109Y345609D03*
X276869D03*
X283629D03*
X290389D03*
X266729Y343660D03*
X273489D03*
X280249D03*
X287009D03*
X270109Y372909D03*
X276869D03*
X283629D03*
X290389D03*
X297149Y216909D03*
X303909D03*
X310668D03*
X317428D03*
X324188D03*
X330948D03*
X337708D03*
X344468D03*
X351228D03*
X293769Y214960D03*
X300529D03*
X307289D03*
X314048D03*
X320808D03*
X327568D03*
X334328D03*
X341088D03*
X347848D03*
X354607D03*
X297149Y213009D03*
X303909D03*
X310668D03*
X317428D03*
X324188D03*
X330948D03*
X337708D03*
X344468D03*
X351228D03*
X293769Y211060D03*
X300529D03*
X307289D03*
X314048D03*
X320808D03*
X327568D03*
X334328D03*
X341088D03*
X347848D03*
X354607D03*
X297149Y209109D03*
X303909D03*
X310668D03*
X317428D03*
X324188D03*
X330948D03*
X337708D03*
X344468D03*
X351228D03*
X293769Y207159D03*
X300529D03*
X307289D03*
X314048D03*
X320808D03*
X327568D03*
X334328D03*
X341088D03*
X347848D03*
X354607D03*
X297149Y205210D03*
X303909D03*
X310668D03*
X317428D03*
X324188D03*
X330948D03*
X337708D03*
X344468D03*
X351228D03*
X293769Y203260D03*
X300529D03*
X307289D03*
X314048D03*
X334328D03*
X341088D03*
X347848D03*
X354607D03*
X297149Y201309D03*
X303909D03*
X310668D03*
X317428D03*
X337708D03*
X344468D03*
X351228D03*
X293769Y199360D03*
X300529D03*
X307289D03*
X314048D03*
X341088D03*
X347848D03*
X354607D03*
X297149Y197409D03*
X303909D03*
X310668D03*
X317428D03*
X344468D03*
X351228D03*
X297149Y232509D03*
X303909D03*
X310668D03*
X317428D03*
X324188D03*
X330948D03*
X337708D03*
X344468D03*
X351228D03*
X293769Y230559D03*
X300529D03*
X307289D03*
X314048D03*
X320808D03*
X327568D03*
X334328D03*
X341088D03*
X347848D03*
X354607D03*
X297149Y228610D03*
X303909D03*
X310668D03*
X317428D03*
X324188D03*
X330948D03*
X337708D03*
X344468D03*
X351228D03*
X293769Y226660D03*
X300529D03*
X307289D03*
X314048D03*
X320808D03*
X327568D03*
X334328D03*
X341088D03*
X347848D03*
X354607D03*
X297149Y224709D03*
X303909D03*
X310668D03*
X317428D03*
X324188D03*
X330948D03*
X337708D03*
X344468D03*
X351228D03*
X297149Y220809D03*
X303909D03*
X310668D03*
X317428D03*
X324188D03*
X330948D03*
X337708D03*
X344468D03*
X351228D03*
X293769Y218860D03*
X300529D03*
X307289D03*
X314048D03*
X320808D03*
X327568D03*
X334328D03*
X341088D03*
X347848D03*
X354607D03*
X297149Y279310D03*
X303909D03*
X310668D03*
X317428D03*
X324188D03*
X330948D03*
X337708D03*
X344468D03*
X351228D03*
X293769Y277360D03*
X300529D03*
X307289D03*
X314048D03*
X320808D03*
X327568D03*
X334328D03*
X341088D03*
X347848D03*
X297149Y275409D03*
X303909D03*
X310668D03*
X317428D03*
X324188D03*
X330948D03*
X337708D03*
X344468D03*
X351228D03*
X293769Y273460D03*
X300529D03*
X307289D03*
X314048D03*
X320808D03*
X327568D03*
X334328D03*
X341088D03*
X347848D03*
X297149Y271509D03*
X303909D03*
X310668D03*
X317428D03*
X324188D03*
X330948D03*
X337708D03*
X344468D03*
X351228D03*
X293769Y269560D03*
X300529D03*
X307289D03*
X314048D03*
X320808D03*
X327568D03*
X334328D03*
X341088D03*
X347848D03*
X297149Y267609D03*
X303909D03*
X310668D03*
X317428D03*
X324188D03*
X330948D03*
X337708D03*
X344468D03*
X351228D03*
X293769Y265660D03*
X300529D03*
X307289D03*
X314048D03*
X320808D03*
X327568D03*
X334328D03*
X341088D03*
X347848D03*
X354607D03*
X297149Y263709D03*
X303909D03*
X310668D03*
X317428D03*
X324188D03*
X330948D03*
X337708D03*
X344468D03*
X351228D03*
X293769Y261760D03*
X300529D03*
X307289D03*
X314048D03*
X327568D03*
X334328D03*
X341088D03*
X347848D03*
X354607D03*
X297149Y259809D03*
X303909D03*
X310668D03*
X324188D03*
X330948D03*
X337708D03*
X344468D03*
X351228D03*
X293769Y257860D03*
X300529D03*
X307289D03*
X327568D03*
X334328D03*
X341088D03*
X347848D03*
X354607D03*
X297149Y255909D03*
X303909D03*
X310668D03*
X324188D03*
X330948D03*
X337708D03*
X344468D03*
X351228D03*
X293769Y253960D03*
X300529D03*
X307289D03*
X327568D03*
X334328D03*
X341088D03*
X347848D03*
X354607D03*
X297149Y252009D03*
X303909D03*
X310668D03*
X324188D03*
X330948D03*
X337708D03*
X344468D03*
X351228D03*
X293769Y250060D03*
X300529D03*
X307289D03*
X320808D03*
X327568D03*
X334328D03*
X341088D03*
X347848D03*
X354607D03*
X297149Y248109D03*
X303909D03*
X310668D03*
X317428D03*
X324188D03*
X330948D03*
X337708D03*
X344468D03*
X351228D03*
X293769Y246160D03*
X300529D03*
X307289D03*
X314048D03*
X320808D03*
X327568D03*
X334328D03*
X341088D03*
X347848D03*
X354607D03*
X297149Y244209D03*
X303909D03*
X310668D03*
X317428D03*
X324188D03*
X330948D03*
X337708D03*
X344468D03*
X351228D03*
X293769Y242260D03*
X300529D03*
X307289D03*
X314048D03*
X320808D03*
X327568D03*
X334328D03*
X341088D03*
X347848D03*
X354607D03*
X297149Y240309D03*
X303909D03*
X310668D03*
X317428D03*
X324188D03*
X330948D03*
X337708D03*
X344468D03*
X351228D03*
X293769Y238360D03*
X300529D03*
X307289D03*
X314048D03*
X320808D03*
X327568D03*
X334328D03*
X341088D03*
X347848D03*
X354607D03*
X297149Y236409D03*
X303909D03*
X310668D03*
X317428D03*
X324188D03*
X330948D03*
X337708D03*
X344468D03*
X351228D03*
X293769Y234460D03*
X300529D03*
X307289D03*
X314048D03*
X320808D03*
X327568D03*
X334328D03*
X341088D03*
X347848D03*
X354607D03*
X293769Y222760D03*
X300529D03*
X307289D03*
X314048D03*
X320808D03*
X327568D03*
X334328D03*
X341088D03*
X347848D03*
X354607D03*
X297149Y341709D03*
X303909D03*
X310668D03*
X324188D03*
X330948D03*
X337708D03*
X344468D03*
X351228D03*
X293769Y339760D03*
X300529D03*
X307289D03*
X327568D03*
X334328D03*
X341088D03*
X347848D03*
X354607D03*
X297149Y337809D03*
X303909D03*
X310668D03*
X324188D03*
X330948D03*
X337708D03*
X344468D03*
X351228D03*
X293769Y335860D03*
X300529D03*
X307289D03*
X320808D03*
X327568D03*
X334328D03*
X341088D03*
X347848D03*
X354607D03*
X297149Y333909D03*
X303909D03*
X310668D03*
X317428D03*
X324188D03*
X330948D03*
X337708D03*
X344468D03*
X351228D03*
X293769Y331960D03*
X300529D03*
X307289D03*
X314048D03*
X320808D03*
X327568D03*
X334328D03*
X341088D03*
X347848D03*
X354607D03*
X297149Y330009D03*
X303909D03*
X310668D03*
X317428D03*
X324188D03*
X330948D03*
X337708D03*
X344468D03*
X351228D03*
X293769Y328060D03*
X300529D03*
X307289D03*
X314048D03*
X320808D03*
X327568D03*
X334328D03*
X341088D03*
X347848D03*
X297149Y326110D03*
X303909D03*
X310668D03*
X317428D03*
X324188D03*
X330948D03*
X337708D03*
X344468D03*
X351228D03*
X293769Y324160D03*
X300529D03*
X307289D03*
X314048D03*
X320808D03*
X327568D03*
X334328D03*
X341088D03*
X347848D03*
X297149Y322209D03*
X303909D03*
X310668D03*
X317428D03*
X324188D03*
X330948D03*
X337708D03*
X344468D03*
X351228D03*
X293769Y320260D03*
X300529D03*
X307289D03*
X314048D03*
X320808D03*
X327568D03*
X334328D03*
X341088D03*
X347848D03*
X297149Y318309D03*
X303909D03*
X310668D03*
X317428D03*
X324188D03*
X330948D03*
X337708D03*
X344468D03*
X351228D03*
X293769Y316360D03*
X300529D03*
X307289D03*
X314048D03*
X320808D03*
X327568D03*
X334328D03*
X341088D03*
X347848D03*
X297149Y314409D03*
X303909D03*
X310668D03*
X317428D03*
X324188D03*
X330948D03*
X337708D03*
X344468D03*
X351228D03*
X293769Y312460D03*
X300529D03*
X307289D03*
X314048D03*
X320808D03*
X327568D03*
X334328D03*
X341088D03*
X347848D03*
X297149Y310509D03*
X303909D03*
X310668D03*
X317428D03*
X324188D03*
X330948D03*
X337708D03*
X344468D03*
X351228D03*
X293769Y308560D03*
X300529D03*
X307289D03*
X314048D03*
X320808D03*
X327568D03*
X334328D03*
X341088D03*
X347848D03*
X297149Y306609D03*
X303909D03*
X310668D03*
X317428D03*
X324188D03*
X330948D03*
X337708D03*
X344468D03*
X351228D03*
X293769Y304660D03*
X300529D03*
X307289D03*
X314048D03*
X320808D03*
X327568D03*
X334328D03*
X341088D03*
X347848D03*
X297149Y302709D03*
X303909D03*
X310668D03*
X317428D03*
X324188D03*
X330948D03*
X337708D03*
X344468D03*
X351228D03*
X293769Y300760D03*
X300529D03*
X307289D03*
X314048D03*
X320808D03*
X327568D03*
X334328D03*
X341088D03*
X347848D03*
X297149Y298809D03*
X303909D03*
X310668D03*
X317428D03*
X324188D03*
X330948D03*
X337708D03*
X344468D03*
X351228D03*
X293769Y296860D03*
X300529D03*
X307289D03*
X314048D03*
X320808D03*
X327568D03*
X334328D03*
X341088D03*
X347848D03*
X297149Y294909D03*
X303909D03*
X310668D03*
X317428D03*
X324188D03*
X330948D03*
X337708D03*
X344468D03*
X351228D03*
X293769Y292959D03*
X300529D03*
X307289D03*
X314048D03*
X320808D03*
X327568D03*
X334328D03*
X341088D03*
X347848D03*
X297149Y291009D03*
X303909D03*
X310668D03*
X317428D03*
X324188D03*
X330948D03*
X337708D03*
X344468D03*
X351228D03*
X293769Y289060D03*
X300529D03*
X307289D03*
X314048D03*
X320808D03*
X327568D03*
X334328D03*
X341088D03*
X347848D03*
X297149Y287109D03*
X303909D03*
X310668D03*
X317428D03*
X324188D03*
X330948D03*
X337708D03*
X344468D03*
X351228D03*
X293769Y285160D03*
X300529D03*
X307289D03*
X314048D03*
X320808D03*
X327568D03*
X334328D03*
X341088D03*
X347848D03*
X297149Y283209D03*
X303909D03*
X310668D03*
X317428D03*
X324188D03*
X330948D03*
X337708D03*
X344468D03*
X351228D03*
X293769Y281260D03*
X300529D03*
X307289D03*
X314048D03*
X320808D03*
X327568D03*
X334328D03*
X341088D03*
X347848D03*
X297149Y400209D03*
X303909D03*
X310668D03*
X317428D03*
X344468D03*
X351228D03*
X293769Y398260D03*
X300529D03*
X307289D03*
X314048D03*
X320808D03*
X347848D03*
X354607D03*
X297149Y396309D03*
X303909D03*
X310668D03*
X317428D03*
X324188D03*
X344468D03*
X351228D03*
X293769Y394359D03*
X300529D03*
X307289D03*
X314048D03*
X320808D03*
X347848D03*
X354607D03*
X297149Y392410D03*
X303909D03*
X310668D03*
X317428D03*
X324188D03*
X330948D03*
X337708D03*
X344468D03*
X351228D03*
X293769Y390460D03*
X300529D03*
X307289D03*
X314048D03*
X320808D03*
X327568D03*
X334328D03*
X341088D03*
X347848D03*
X354607D03*
X297149Y388509D03*
X303909D03*
X310668D03*
X317428D03*
X324188D03*
X330948D03*
X337708D03*
X344468D03*
X351228D03*
X293769Y386560D03*
X300529D03*
X307289D03*
X314048D03*
X320808D03*
X327568D03*
X334328D03*
X341088D03*
X347848D03*
X354607D03*
X297149Y384609D03*
X303909D03*
X310668D03*
X317428D03*
X324188D03*
X330948D03*
X337708D03*
X344468D03*
X351228D03*
X293769Y382660D03*
X300529D03*
X307289D03*
X314048D03*
X320808D03*
X327568D03*
X334328D03*
X341088D03*
X347848D03*
X354607D03*
X297149Y380709D03*
X303909D03*
X310668D03*
X317428D03*
X324188D03*
X330948D03*
X337708D03*
X344468D03*
X351228D03*
X293769Y378760D03*
X300529D03*
X307289D03*
X314048D03*
X320808D03*
X327568D03*
X334328D03*
X341088D03*
X347848D03*
X354607D03*
X297149Y376809D03*
X303909D03*
X310668D03*
X317428D03*
X324188D03*
X330948D03*
X337708D03*
X344468D03*
X351228D03*
X293769Y374860D03*
X300529D03*
X307289D03*
X314048D03*
X320808D03*
X327568D03*
X334328D03*
X341088D03*
X347848D03*
X354607D03*
X293769Y370959D03*
X300529D03*
X307289D03*
X314048D03*
X320808D03*
X327568D03*
X334328D03*
X341088D03*
X347848D03*
X354607D03*
X297149Y369010D03*
X303909D03*
X310668D03*
X317428D03*
X324188D03*
X330948D03*
X337708D03*
X344468D03*
X351228D03*
X293769Y367060D03*
X300529D03*
X307289D03*
X314048D03*
X320808D03*
X327568D03*
X334328D03*
X341088D03*
X347848D03*
X354607D03*
X297149Y365109D03*
X303909D03*
X310668D03*
X317428D03*
X324188D03*
X330948D03*
X337708D03*
X344468D03*
X351228D03*
X293769Y363160D03*
X300529D03*
X307289D03*
X314048D03*
X320808D03*
X327568D03*
X334328D03*
X341088D03*
X347848D03*
X354607D03*
X297149Y361209D03*
X303909D03*
X310668D03*
X317428D03*
X324188D03*
X330948D03*
X337708D03*
X344468D03*
X351228D03*
X293769Y359260D03*
X300529D03*
X307289D03*
X314048D03*
X320808D03*
X327568D03*
X334328D03*
X341088D03*
X347848D03*
X354607D03*
X297149Y357309D03*
X303909D03*
X310668D03*
X317428D03*
X324188D03*
X330948D03*
X337708D03*
X344468D03*
X351228D03*
X293769Y355360D03*
X300529D03*
X307289D03*
X314048D03*
X320808D03*
X327568D03*
X334328D03*
X341088D03*
X347848D03*
X354607D03*
X297149Y353409D03*
X303909D03*
X310668D03*
X317428D03*
X324188D03*
X330948D03*
X337708D03*
X344468D03*
X351228D03*
X293769Y351460D03*
X300529D03*
X307289D03*
X314048D03*
X320808D03*
X327568D03*
X334328D03*
X341088D03*
X347848D03*
X354607D03*
X297149Y349509D03*
X303909D03*
X310668D03*
X317428D03*
X324188D03*
X330948D03*
X337708D03*
X344468D03*
X351228D03*
X293769Y347560D03*
X300529D03*
X307289D03*
X314048D03*
X327568D03*
X334328D03*
X341088D03*
X347848D03*
X354607D03*
X297149Y345609D03*
X303909D03*
X310668D03*
X324188D03*
X330948D03*
X337708D03*
X344468D03*
X351228D03*
X293769Y343660D03*
X300529D03*
X307289D03*
X327568D03*
X334328D03*
X341088D03*
X347848D03*
X354607D03*
X297149Y372909D03*
X303909D03*
X310668D03*
X317428D03*
X324188D03*
X330948D03*
X337708D03*
X344468D03*
X351228D03*
X357987Y216909D03*
X364747D03*
X371507D03*
X378267D03*
X385027D03*
X391787D03*
X398546D03*
X361367Y214960D03*
X368127D03*
X374887D03*
X381647D03*
X388407D03*
X395166D03*
X401926D03*
X357987Y213009D03*
X364747D03*
X371507D03*
X378267D03*
X385027D03*
X391787D03*
X398546D03*
X361367Y211060D03*
X368127D03*
X374887D03*
X381647D03*
X388407D03*
X395166D03*
X401926D03*
X357987Y209109D03*
X364747D03*
X371507D03*
X378267D03*
X385027D03*
X391787D03*
X398546D03*
X361367Y207159D03*
X368127D03*
X374887D03*
X381647D03*
X388407D03*
X395166D03*
X401926D03*
X357987Y205210D03*
X364747D03*
X371507D03*
X378267D03*
X385027D03*
X391787D03*
X398546D03*
X361367Y203260D03*
X368127D03*
X374887D03*
X381647D03*
X388407D03*
X395166D03*
X401926D03*
X357987Y201309D03*
X364747D03*
X371507D03*
X378267D03*
X385027D03*
X391787D03*
X398546D03*
X405306D03*
X361367Y199360D03*
X368127D03*
X374887D03*
X381647D03*
X388407D03*
X395166D03*
X401926D03*
X357987Y197409D03*
X364747D03*
X371507D03*
X378267D03*
X385027D03*
X391787D03*
X398546D03*
X357987Y232509D03*
X364747D03*
X371507D03*
X378267D03*
X385027D03*
X391787D03*
X398546D03*
X361367Y230559D03*
X368127D03*
X374887D03*
X381647D03*
X388407D03*
X395166D03*
X401926D03*
X357987Y228610D03*
X364747D03*
X371507D03*
X378267D03*
X385027D03*
X391787D03*
X398546D03*
X361367Y226660D03*
X368127D03*
X374887D03*
X381647D03*
X388407D03*
X395166D03*
X401926D03*
X357987Y224709D03*
X364747D03*
X371507D03*
X378267D03*
X385027D03*
X391787D03*
X398546D03*
X357987Y220809D03*
X364747D03*
X371507D03*
X378267D03*
X385027D03*
X391787D03*
X398546D03*
X361367Y218860D03*
X368127D03*
X374887D03*
X381647D03*
X388407D03*
X395166D03*
X401926D03*
X357987Y263709D03*
X361367Y261760D03*
X357987Y259809D03*
X364747D03*
X361367Y257860D03*
X368127D03*
X357987Y255909D03*
X364747D03*
X371507D03*
X361367Y253960D03*
X368127D03*
X374887D03*
X357987Y252009D03*
X364747D03*
X371507D03*
X378267D03*
X385027D03*
X391787D03*
X398546D03*
X361367Y250060D03*
X368127D03*
X374887D03*
X381647D03*
X388407D03*
X395166D03*
X401926D03*
X357987Y248109D03*
X364747D03*
X371507D03*
X378267D03*
X385027D03*
X391787D03*
X398546D03*
X361367Y246160D03*
X368127D03*
X374887D03*
X381647D03*
X388407D03*
X395166D03*
X401926D03*
X357987Y244209D03*
X364747D03*
X371507D03*
X378267D03*
X385027D03*
X391787D03*
X398546D03*
X361367Y242260D03*
X368127D03*
X374887D03*
X381647D03*
X388407D03*
X395166D03*
X401926D03*
X357987Y240309D03*
X364747D03*
X371507D03*
X378267D03*
X385027D03*
X391787D03*
X398546D03*
X361367Y238360D03*
X368127D03*
X374887D03*
X381647D03*
X388407D03*
X395166D03*
X401926D03*
X357987Y236409D03*
X364747D03*
X371507D03*
X378267D03*
X385027D03*
X391787D03*
X398546D03*
X361367Y234460D03*
X368127D03*
X374887D03*
X381647D03*
X388407D03*
X395166D03*
X401926D03*
X361367Y222760D03*
X368127D03*
X374887D03*
X381647D03*
X388407D03*
X395166D03*
X401926D03*
X357987Y341709D03*
X364747D03*
X371507D03*
X361367Y339760D03*
X368127D03*
X357987Y337809D03*
X364747D03*
X361367Y335860D03*
X357987Y333909D03*
Y400209D03*
X364747D03*
X371507D03*
X378267D03*
X385027D03*
X391787D03*
X398546D03*
X405306D03*
X361367Y398260D03*
X368127D03*
X374887D03*
X381647D03*
X388407D03*
X395166D03*
X401926D03*
X408686D03*
X357987Y396309D03*
X364747D03*
X371507D03*
X378267D03*
X385027D03*
X391787D03*
X398546D03*
X405306D03*
X361367Y394359D03*
X368127D03*
X374887D03*
X381647D03*
X388407D03*
X395166D03*
X401926D03*
X357987Y392410D03*
X364747D03*
X371507D03*
X378267D03*
X385027D03*
X391787D03*
X398546D03*
X405306D03*
X361367Y390460D03*
X368127D03*
X374887D03*
X381647D03*
X388407D03*
X395166D03*
X401926D03*
X357987Y388509D03*
X364747D03*
X371507D03*
X378267D03*
X385027D03*
X391787D03*
X398546D03*
X405306D03*
X361367Y386560D03*
X368127D03*
X374887D03*
X381647D03*
X388407D03*
X395166D03*
X401926D03*
X357987Y384609D03*
X364747D03*
X371507D03*
X378267D03*
X385027D03*
X391787D03*
X398546D03*
X405306D03*
X361367Y382660D03*
X368127D03*
X374887D03*
X381647D03*
X388407D03*
X395166D03*
X401926D03*
X357987Y380709D03*
X364747D03*
X371507D03*
X378267D03*
X385027D03*
X391787D03*
X398546D03*
X405306D03*
X361367Y378760D03*
X368127D03*
X374887D03*
X381647D03*
X388407D03*
X395166D03*
X401926D03*
X357987Y376809D03*
X364747D03*
X371507D03*
X378267D03*
X385027D03*
X391787D03*
X398546D03*
X405306D03*
X361367Y374860D03*
X368127D03*
X374887D03*
X381647D03*
X388407D03*
X395166D03*
X401926D03*
X361367Y370959D03*
X368127D03*
X374887D03*
X381647D03*
X388407D03*
X395166D03*
X401926D03*
X357987Y369010D03*
X364747D03*
X371507D03*
X378267D03*
X385027D03*
X391787D03*
X398546D03*
X405306D03*
X361367Y367060D03*
X368127D03*
X374887D03*
X381647D03*
X388407D03*
X395166D03*
X401926D03*
X357987Y365109D03*
X364747D03*
X371507D03*
X378267D03*
X385027D03*
X391787D03*
X398546D03*
X405306D03*
X361367Y363160D03*
X368127D03*
X374887D03*
X381647D03*
X388407D03*
X395166D03*
X401926D03*
X357987Y361209D03*
X364747D03*
X371507D03*
X378267D03*
X385027D03*
X391787D03*
X398546D03*
X405306D03*
X361367Y359260D03*
X368127D03*
X374887D03*
X381647D03*
X388407D03*
X395166D03*
X401926D03*
X357987Y357309D03*
X364747D03*
X371507D03*
X378267D03*
X385027D03*
X391787D03*
X398546D03*
X405306D03*
X361367Y355360D03*
X368127D03*
X374887D03*
X381647D03*
X388407D03*
X395166D03*
X401926D03*
X357987Y353409D03*
X364747D03*
X371507D03*
X378267D03*
X385027D03*
X391787D03*
X398546D03*
X405306D03*
X361367Y351460D03*
X368127D03*
X374887D03*
X381647D03*
X388407D03*
X395166D03*
X401926D03*
X357987Y349509D03*
X364747D03*
X371507D03*
X378267D03*
X385027D03*
X391787D03*
X398546D03*
X361367Y347560D03*
X368127D03*
X374887D03*
X381647D03*
X357987Y345609D03*
X364747D03*
X371507D03*
X378267D03*
X361367Y343660D03*
X368127D03*
X374887D03*
X357987Y372909D03*
X364747D03*
X371507D03*
X378267D03*
X385027D03*
X391787D03*
X398546D03*
X405306D03*
X421464Y218147D03*
X428224D03*
X434983D03*
X441743D03*
X448503D03*
X455263D03*
X462023D03*
X468783D03*
X475542D03*
X418084Y216196D03*
X424844D03*
X431604D03*
X438363D03*
X445123D03*
X451883D03*
X458643D03*
X465403D03*
X472163D03*
X421464Y214247D03*
X428224D03*
X434983D03*
X441743D03*
X448503D03*
X455263D03*
X462023D03*
X468783D03*
X475542D03*
X418084Y212296D03*
X424844D03*
X431604D03*
X438363D03*
X445123D03*
X451883D03*
X458643D03*
X465403D03*
X472163D03*
X421464Y210346D03*
X428224D03*
X434983D03*
X441743D03*
X448503D03*
X455263D03*
X462023D03*
X468783D03*
X475542D03*
X418084Y208397D03*
X424844D03*
X431604D03*
X438363D03*
X445123D03*
X451883D03*
X458643D03*
X465403D03*
X472163D03*
X421464Y206447D03*
X428224D03*
X434983D03*
X441743D03*
X448503D03*
X455263D03*
X462023D03*
X468783D03*
X475542D03*
X418084Y204496D03*
X424844D03*
X431604D03*
X438363D03*
X445123D03*
X451883D03*
X458643D03*
X465403D03*
X472163D03*
X421464Y202547D03*
X428224D03*
X434983D03*
X441743D03*
X448503D03*
X455263D03*
X462023D03*
X468783D03*
X475542D03*
X418084Y239596D03*
X424844D03*
X431604D03*
X438363D03*
X445123D03*
X451883D03*
X458643D03*
X465403D03*
X472163D03*
X421464Y237647D03*
X428224D03*
X434983D03*
X441743D03*
X448503D03*
X455263D03*
X462023D03*
X468783D03*
X475542D03*
X418084Y235696D03*
X424844D03*
X431604D03*
X438363D03*
X445123D03*
X451883D03*
X458643D03*
X465403D03*
X472163D03*
X421464Y233746D03*
X428224D03*
X434983D03*
X441743D03*
X448503D03*
X455263D03*
X462023D03*
X468783D03*
X475542D03*
X418084Y231797D03*
X424844D03*
X431604D03*
X438363D03*
X445123D03*
X451883D03*
X458643D03*
X465403D03*
X472163D03*
X418084Y227896D03*
X424844D03*
X431604D03*
X438363D03*
X445123D03*
X451883D03*
X458643D03*
X465403D03*
X472163D03*
X421464Y225947D03*
X428224D03*
X434983D03*
X441743D03*
X448503D03*
X455263D03*
X462023D03*
X468783D03*
X475542D03*
X418084Y223996D03*
X424844D03*
X431604D03*
X438363D03*
X445123D03*
X451883D03*
X458643D03*
X465403D03*
X472163D03*
X421464Y222047D03*
X428224D03*
X434983D03*
X441743D03*
X448503D03*
X455263D03*
X462023D03*
X468783D03*
X475542D03*
X418084Y220096D03*
X424844D03*
X431604D03*
X438363D03*
X445123D03*
X451883D03*
X458643D03*
X465403D03*
X472163D03*
Y278596D03*
X475542Y276646D03*
X472163Y274696D03*
X468783Y272747D03*
X475542D03*
X465403Y270796D03*
X472163D03*
X462023Y268847D03*
X468783D03*
X475542D03*
X458643Y266896D03*
X465403D03*
X472163D03*
X455263Y264947D03*
X462023D03*
X468783D03*
X475542D03*
X451883Y262996D03*
X458643D03*
X465403D03*
X472163D03*
X448503Y261047D03*
X455263D03*
X462023D03*
X468783D03*
X475542D03*
X445123Y259096D03*
X451883D03*
X458643D03*
X465403D03*
X472163D03*
X441743Y257147D03*
X448503D03*
X455263D03*
X462023D03*
X468783D03*
X475542D03*
X424844Y255196D03*
X431604D03*
X438363D03*
X445123D03*
X451883D03*
X458643D03*
X465403D03*
X472163D03*
X421464Y253247D03*
X428224D03*
X434983D03*
X441743D03*
X448503D03*
X455263D03*
X462023D03*
X468783D03*
X475542D03*
X418084Y251296D03*
X424844D03*
X431604D03*
X438363D03*
X445123D03*
X451883D03*
X458643D03*
X465403D03*
X472163D03*
X421464Y249347D03*
X428224D03*
X434983D03*
X441743D03*
X448503D03*
X455263D03*
X462023D03*
X468783D03*
X475542D03*
X418084Y247396D03*
X424844D03*
X431604D03*
X438363D03*
X445123D03*
X451883D03*
X458643D03*
X465403D03*
X472163D03*
X421464Y245447D03*
X428224D03*
X434983D03*
X441743D03*
X448503D03*
X455263D03*
X462023D03*
X468783D03*
X475542D03*
X418084Y243496D03*
X424844D03*
X431604D03*
X438363D03*
X445123D03*
X451883D03*
X458643D03*
X465403D03*
X472163D03*
X421464Y241547D03*
X428224D03*
X434983D03*
X441743D03*
X448503D03*
X455263D03*
X462023D03*
X468783D03*
X475542D03*
X421464Y229847D03*
X428224D03*
X434983D03*
X441743D03*
X448503D03*
X455263D03*
X462023D03*
X468783D03*
X475542D03*
X458643Y340996D03*
X465403D03*
X472163D03*
X462023Y339047D03*
X468783D03*
X475542D03*
X465403Y337096D03*
X472163D03*
X468783Y335147D03*
X475542D03*
X472163Y333196D03*
X475542Y331247D03*
X472163Y329296D03*
X475542Y327347D03*
X472163Y325396D03*
X475542Y323446D03*
X472163Y321496D03*
X475542Y319547D03*
X472163Y317596D03*
X475542Y315647D03*
X472163Y313696D03*
X475542Y311747D03*
X472163Y309797D03*
X475542Y307847D03*
X472163Y305896D03*
X475542Y303947D03*
X472163Y301996D03*
X475542Y300047D03*
X472163Y298096D03*
X475542Y296147D03*
X472163Y294196D03*
X475542Y292247D03*
X472163Y290296D03*
X475542Y288347D03*
X472163Y286396D03*
X475542Y284447D03*
X472163Y282496D03*
X475542Y280547D03*
X424844Y403396D03*
X431604D03*
X438363D03*
X445123D03*
X451883D03*
X458643D03*
X465403D03*
X472163D03*
X421464Y401447D03*
X428224D03*
X434983D03*
X441743D03*
X448503D03*
X455263D03*
X462023D03*
X468783D03*
X475542D03*
X424844Y399496D03*
X431604D03*
X438363D03*
X445123D03*
X451883D03*
X458643D03*
X465403D03*
X472163D03*
X421464Y397546D03*
X428224D03*
X434983D03*
X441743D03*
X448503D03*
X455263D03*
X462023D03*
X468783D03*
X475542D03*
X424844Y395597D03*
X431604D03*
X438363D03*
X445123D03*
X451883D03*
X458643D03*
X465403D03*
X472163D03*
X421464Y393647D03*
X428224D03*
X434983D03*
X441743D03*
X448503D03*
X455263D03*
X462023D03*
X468783D03*
X475542D03*
X424844Y391696D03*
X431604D03*
X438363D03*
X445123D03*
X451883D03*
X458643D03*
X465403D03*
X472163D03*
X421464Y389747D03*
X428224D03*
X434983D03*
X441743D03*
X448503D03*
X455263D03*
X462023D03*
X468783D03*
X475542D03*
X424844Y387796D03*
X431604D03*
X438363D03*
X445123D03*
X451883D03*
X458643D03*
X465403D03*
X472163D03*
X421464Y385847D03*
X428224D03*
X434983D03*
X441743D03*
X448503D03*
X455263D03*
X462023D03*
X468783D03*
X475542D03*
X424844Y383896D03*
X431604D03*
X438363D03*
X445123D03*
X451883D03*
X458643D03*
X465403D03*
X472163D03*
X421464Y381947D03*
X428224D03*
X434983D03*
X441743D03*
X448503D03*
X455263D03*
X462023D03*
X468783D03*
X475542D03*
X421464Y378047D03*
X428224D03*
X434983D03*
X441743D03*
X448503D03*
X455263D03*
X462023D03*
X468783D03*
X475542D03*
X424844Y376096D03*
X431604D03*
X438363D03*
X445123D03*
X451883D03*
X458643D03*
X465403D03*
X472163D03*
X421464Y374146D03*
X428224D03*
X434983D03*
X441743D03*
X448503D03*
X455263D03*
X462023D03*
X468783D03*
X475542D03*
X424844Y372197D03*
X431604D03*
X438363D03*
X445123D03*
X451883D03*
X458643D03*
X465403D03*
X472163D03*
X421464Y370247D03*
X428224D03*
X434983D03*
X441743D03*
X448503D03*
X455263D03*
X462023D03*
X468783D03*
X475542D03*
X424844Y368296D03*
X431604D03*
X438363D03*
X445123D03*
X451883D03*
X458643D03*
X465403D03*
X472163D03*
X421464Y366347D03*
X428224D03*
X434983D03*
X441743D03*
X448503D03*
X455263D03*
X462023D03*
X468783D03*
X475542D03*
X424844Y364396D03*
X431604D03*
X438363D03*
X445123D03*
X451883D03*
X458643D03*
X465403D03*
X472163D03*
X421464Y362447D03*
X428224D03*
X434983D03*
X441743D03*
X448503D03*
X455263D03*
X462023D03*
X468783D03*
X475542D03*
X424844Y360496D03*
X431604D03*
X438363D03*
X445123D03*
X451883D03*
X458643D03*
X465403D03*
X472163D03*
X421464Y358547D03*
X428224D03*
X434983D03*
X441743D03*
X448503D03*
X455263D03*
X462023D03*
X468783D03*
X475542D03*
X424844Y356596D03*
X431604D03*
X438363D03*
X445123D03*
X451883D03*
X458643D03*
X465403D03*
X472163D03*
X421464Y354647D03*
X428224D03*
X434983D03*
X441743D03*
X448503D03*
X455263D03*
X462023D03*
X468783D03*
X475542D03*
X424844Y352696D03*
X431604D03*
X438363D03*
X445123D03*
X451883D03*
X458643D03*
X465403D03*
X472163D03*
X421464Y350747D03*
X428224D03*
X434983D03*
X441743D03*
X448503D03*
X455263D03*
X462023D03*
X468783D03*
X475542D03*
X424844Y348796D03*
X431604D03*
X438363D03*
X445123D03*
X451883D03*
X458643D03*
X465403D03*
X472163D03*
X448503Y346847D03*
X455263D03*
X462023D03*
X468783D03*
X475542D03*
X451883Y344896D03*
X458643D03*
X465403D03*
X472163D03*
X455263Y342947D03*
X462023D03*
X468783D03*
X475542D03*
X424844Y379996D03*
X431604D03*
X438363D03*
X445123D03*
X451883D03*
X458643D03*
X465403D03*
X472163D03*
X428224Y405347D03*
X434983D03*
X441743D03*
X448503D03*
X455263D03*
X462023D03*
X468783D03*
X475542D03*
X536381Y218147D03*
X482302D03*
X489062D03*
X495822D03*
X502582D03*
X509342D03*
X516102D03*
X522861D03*
X529621D03*
X533001Y216196D03*
X539761D03*
X478922D03*
X485682D03*
X492442D03*
X499202D03*
X505962D03*
X512722D03*
X519481D03*
X526241D03*
X536381Y214247D03*
X482302D03*
X489062D03*
X495822D03*
X502582D03*
X509342D03*
X516102D03*
X522861D03*
X529621D03*
X533001Y212296D03*
X539761D03*
X478922D03*
X485682D03*
X492442D03*
X499202D03*
X505962D03*
X512722D03*
X519481D03*
X526241D03*
X536381Y210346D03*
X482302D03*
X489062D03*
X495822D03*
X502582D03*
X509342D03*
X516102D03*
X522861D03*
X529621D03*
X533001Y208397D03*
X539761D03*
X478922D03*
X505962D03*
X512722D03*
X519481D03*
X526241D03*
X536381Y206447D03*
X482302D03*
X502582D03*
X509342D03*
X516102D03*
X522861D03*
X529621D03*
X533001Y204496D03*
X539761D03*
X478922D03*
X505962D03*
X512722D03*
X519481D03*
X526241D03*
X536381Y202547D03*
X482302D03*
X509342D03*
X516102D03*
X522861D03*
X529621D03*
X533001Y239596D03*
X539761D03*
X478922D03*
X485682D03*
X492442D03*
X499202D03*
X505962D03*
X512722D03*
X519481D03*
X526241D03*
X536381Y237647D03*
X482302D03*
X489062D03*
X495822D03*
X502582D03*
X509342D03*
X516102D03*
X522861D03*
X529621D03*
X533001Y235696D03*
X539761D03*
X478922D03*
X485682D03*
X492442D03*
X499202D03*
X505962D03*
X512722D03*
X519481D03*
X526241D03*
X536381Y233746D03*
X482302D03*
X489062D03*
X495822D03*
X502582D03*
X509342D03*
X516102D03*
X522861D03*
X529621D03*
X533001Y231797D03*
X539761D03*
X478922D03*
X485682D03*
X492442D03*
X499202D03*
X505962D03*
X512722D03*
X519481D03*
X526241D03*
X533001Y227896D03*
X539761D03*
X478922D03*
X485682D03*
X492442D03*
X499202D03*
X505962D03*
X512722D03*
X519481D03*
X526241D03*
X536381Y225947D03*
X482302D03*
X489062D03*
X495822D03*
X502582D03*
X509342D03*
X516102D03*
X522861D03*
X529621D03*
X533001Y223996D03*
X539761D03*
X478922D03*
X485682D03*
X492442D03*
X499202D03*
X505962D03*
X512722D03*
X519481D03*
X526241D03*
X536381Y222047D03*
X482302D03*
X489062D03*
X495822D03*
X502582D03*
X509342D03*
X516102D03*
X522861D03*
X529621D03*
X533001Y220096D03*
X539761D03*
X478922D03*
X485682D03*
X492442D03*
X499202D03*
X505962D03*
X512722D03*
X519481D03*
X526241D03*
X533001Y278596D03*
X539761D03*
X478922D03*
X485682D03*
X492442D03*
X499202D03*
X505962D03*
X512722D03*
X519481D03*
X526241D03*
X536381Y276646D03*
X482302D03*
X489062D03*
X495822D03*
X502582D03*
X509342D03*
X516102D03*
X522861D03*
X529621D03*
X533001Y274696D03*
X539761D03*
X478922D03*
X485682D03*
X492442D03*
X499202D03*
X505962D03*
X512722D03*
X519481D03*
X526241D03*
X536381Y272747D03*
X482302D03*
X489062D03*
X495822D03*
X502582D03*
X509342D03*
X516102D03*
X522861D03*
X529621D03*
X533001Y270796D03*
X539761D03*
X478922D03*
X485682D03*
X492442D03*
X499202D03*
X505962D03*
X512722D03*
X519481D03*
X526241D03*
X536381Y268847D03*
X482302D03*
X489062D03*
X495822D03*
X502582D03*
X509342D03*
X516102D03*
X522861D03*
X529621D03*
X533001Y266896D03*
X539761D03*
X478922D03*
X485682D03*
X492442D03*
X499202D03*
X505962D03*
X519481D03*
X526241D03*
X536381Y264947D03*
X482302D03*
X489062D03*
X495822D03*
X502582D03*
X516102D03*
X522861D03*
X529621D03*
X533001Y262996D03*
X539761D03*
X478922D03*
X485682D03*
X492442D03*
X499202D03*
X519481D03*
X526241D03*
X536381Y261047D03*
X482302D03*
X489062D03*
X495822D03*
X502582D03*
X516102D03*
X522861D03*
X529621D03*
X533001Y259096D03*
X539761D03*
X478922D03*
X485682D03*
X492442D03*
X499202D03*
X519481D03*
X526241D03*
X536381Y257147D03*
X482302D03*
X489062D03*
X495822D03*
X502582D03*
X516102D03*
X522861D03*
X529621D03*
X533001Y255196D03*
X539761D03*
X478922D03*
X485682D03*
X492442D03*
X499202D03*
X512722D03*
X519481D03*
X526241D03*
X536381Y253247D03*
X482302D03*
X489062D03*
X495822D03*
X502582D03*
X509342D03*
X516102D03*
X522861D03*
X529621D03*
X533001Y251296D03*
X539761D03*
X478922D03*
X485682D03*
X492442D03*
X499202D03*
X505962D03*
X512722D03*
X519481D03*
X526241D03*
X536381Y249347D03*
X482302D03*
X489062D03*
X495822D03*
X502582D03*
X509342D03*
X516102D03*
X522861D03*
X529621D03*
X533001Y247396D03*
X539761D03*
X478922D03*
X485682D03*
X492442D03*
X499202D03*
X505962D03*
X512722D03*
X519481D03*
X526241D03*
X536381Y245447D03*
X482302D03*
X489062D03*
X495822D03*
X502582D03*
X509342D03*
X516102D03*
X522861D03*
X529621D03*
X533001Y243496D03*
X539761D03*
X478922D03*
X485682D03*
X492442D03*
X499202D03*
X505962D03*
X512722D03*
X519481D03*
X526241D03*
X536381Y241547D03*
X482302D03*
X489062D03*
X495822D03*
X502582D03*
X509342D03*
X516102D03*
X522861D03*
X529621D03*
X536381Y229847D03*
X482302D03*
X489062D03*
X495822D03*
X502582D03*
X509342D03*
X516102D03*
X522861D03*
X529621D03*
X533001Y340996D03*
X539761D03*
X478922D03*
X485682D03*
X492442D03*
X499202D03*
X512722D03*
X519481D03*
X526241D03*
X536381Y339047D03*
X482302D03*
X489062D03*
X495822D03*
X502582D03*
X509342D03*
X516102D03*
X522861D03*
X529621D03*
X533001Y337096D03*
X539761D03*
X478922D03*
X485682D03*
X492442D03*
X499202D03*
X505962D03*
X512722D03*
X519481D03*
X526241D03*
X536381Y335147D03*
X482302D03*
X489062D03*
X495822D03*
X502582D03*
X509342D03*
X516102D03*
X522861D03*
X529621D03*
X533001Y333196D03*
X539761D03*
X478922D03*
X485682D03*
X492442D03*
X499202D03*
X505962D03*
X512722D03*
X519481D03*
X526241D03*
X536381Y331247D03*
X482302D03*
X489062D03*
X495822D03*
X502582D03*
X509342D03*
X516102D03*
X522861D03*
X529621D03*
X533001Y329296D03*
X539761D03*
X478922D03*
X485682D03*
X492442D03*
X499202D03*
X505962D03*
X512722D03*
X519481D03*
X526241D03*
X536381Y327347D03*
X482302D03*
X489062D03*
X495822D03*
X502582D03*
X509342D03*
X516102D03*
X522861D03*
X529621D03*
X533001Y325396D03*
X539761D03*
X478922D03*
X485682D03*
X492442D03*
X499202D03*
X505962D03*
X512722D03*
X519481D03*
X526241D03*
X536381Y323446D03*
X482302D03*
X489062D03*
X495822D03*
X502582D03*
X509342D03*
X516102D03*
X522861D03*
X529621D03*
X533001Y321496D03*
X539761D03*
X478922D03*
X485682D03*
X492442D03*
X499202D03*
X505962D03*
X512722D03*
X519481D03*
X526241D03*
X536381Y319547D03*
X482302D03*
X489062D03*
X495822D03*
X502582D03*
X509342D03*
X516102D03*
X522861D03*
X529621D03*
X533001Y317596D03*
X539761D03*
X478922D03*
X485682D03*
X492442D03*
X499202D03*
X505962D03*
X512722D03*
X519481D03*
X526241D03*
X536381Y315647D03*
X482302D03*
X489062D03*
X495822D03*
X502582D03*
X509342D03*
X516102D03*
X522861D03*
X529621D03*
X533001Y313696D03*
X539761D03*
X478922D03*
X485682D03*
X492442D03*
X499202D03*
X505962D03*
X512722D03*
X519481D03*
X526241D03*
X536381Y311747D03*
X482302D03*
X489062D03*
X495822D03*
X502582D03*
X509342D03*
X516102D03*
X522861D03*
X529621D03*
X533001Y309797D03*
X539761D03*
X478922D03*
X485682D03*
X492442D03*
X499202D03*
X505962D03*
X512722D03*
X519481D03*
X526241D03*
X536381Y307847D03*
X482302D03*
X489062D03*
X495822D03*
X502582D03*
X509342D03*
X516102D03*
X522861D03*
X529621D03*
X533001Y305896D03*
X539761D03*
X478922D03*
X485682D03*
X492442D03*
X499202D03*
X505962D03*
X512722D03*
X519481D03*
X526241D03*
X536381Y303947D03*
X482302D03*
X489062D03*
X495822D03*
X502582D03*
X509342D03*
X516102D03*
X522861D03*
X529621D03*
X533001Y301996D03*
X539761D03*
X478922D03*
X485682D03*
X492442D03*
X499202D03*
X505962D03*
X512722D03*
X519481D03*
X526241D03*
X536381Y300047D03*
X482302D03*
X489062D03*
X495822D03*
X502582D03*
X509342D03*
X516102D03*
X522861D03*
X529621D03*
X533001Y298096D03*
X539761D03*
X478922D03*
X485682D03*
X492442D03*
X499202D03*
X505962D03*
X512722D03*
X519481D03*
X526241D03*
X536381Y296147D03*
X482302D03*
X489062D03*
X495822D03*
X502582D03*
X509342D03*
X516102D03*
X522861D03*
X529621D03*
X533001Y294196D03*
X539761D03*
X478922D03*
X485682D03*
X492442D03*
X499202D03*
X505962D03*
X512722D03*
X519481D03*
X526241D03*
X536381Y292247D03*
X482302D03*
X489062D03*
X495822D03*
X502582D03*
X509342D03*
X516102D03*
X522861D03*
X529621D03*
X533001Y290296D03*
X539761D03*
X478922D03*
X485682D03*
X492442D03*
X499202D03*
X505962D03*
X512722D03*
X519481D03*
X526241D03*
X536381Y288347D03*
X482302D03*
X489062D03*
X495822D03*
X502582D03*
X509342D03*
X516102D03*
X522861D03*
X529621D03*
X533001Y286396D03*
X539761D03*
X478922D03*
X485682D03*
X492442D03*
X499202D03*
X505962D03*
X512722D03*
X519481D03*
X526241D03*
X536381Y284447D03*
X482302D03*
X489062D03*
X495822D03*
X502582D03*
X509342D03*
X516102D03*
X522861D03*
X529621D03*
X533001Y282496D03*
X539761D03*
X478922D03*
X485682D03*
X492442D03*
X499202D03*
X505962D03*
X512722D03*
X519481D03*
X526241D03*
X536381Y280547D03*
X482302D03*
X489062D03*
X495822D03*
X502582D03*
X509342D03*
X516102D03*
X522861D03*
X529621D03*
X533001Y403396D03*
X539761D03*
X478922D03*
X485682D03*
X512722D03*
X519481D03*
X526241D03*
X536381Y401447D03*
X482302D03*
X489062D03*
X509342D03*
X516102D03*
X522861D03*
X529621D03*
X533001Y399496D03*
X539761D03*
X478922D03*
X485682D03*
X492442D03*
X512722D03*
X519481D03*
X526241D03*
X536381Y397546D03*
X482302D03*
X489062D03*
X495822D03*
X502582D03*
X509342D03*
X516102D03*
X522861D03*
X529621D03*
X533001Y395597D03*
X539761D03*
X478922D03*
X485682D03*
X492442D03*
X499202D03*
X505962D03*
X512722D03*
X519481D03*
X526241D03*
X536381Y393647D03*
X482302D03*
X489062D03*
X495822D03*
X502582D03*
X509342D03*
X516102D03*
X522861D03*
X529621D03*
X533001Y391696D03*
X539761D03*
X478922D03*
X485682D03*
X492442D03*
X499202D03*
X505962D03*
X512722D03*
X519481D03*
X526241D03*
X536381Y389747D03*
X482302D03*
X489062D03*
X495822D03*
X502582D03*
X509342D03*
X516102D03*
X522861D03*
X529621D03*
X533001Y387796D03*
X539761D03*
X478922D03*
X485682D03*
X492442D03*
X499202D03*
X505962D03*
X512722D03*
X519481D03*
X526241D03*
X536381Y385847D03*
X482302D03*
X489062D03*
X495822D03*
X502582D03*
X509342D03*
X516102D03*
X522861D03*
X529621D03*
X533001Y383896D03*
X539761D03*
X478922D03*
X485682D03*
X492442D03*
X499202D03*
X505962D03*
X512722D03*
X519481D03*
X526241D03*
X536381Y381947D03*
X482302D03*
X489062D03*
X495822D03*
X502582D03*
X509342D03*
X516102D03*
X522861D03*
X529621D03*
X536381Y378047D03*
X482302D03*
X489062D03*
X495822D03*
X502582D03*
X509342D03*
X516102D03*
X522861D03*
X529621D03*
X533001Y376096D03*
X539761D03*
X478922D03*
X485682D03*
X492442D03*
X499202D03*
X505962D03*
X512722D03*
X519481D03*
X526241D03*
X536381Y374146D03*
X482302D03*
X489062D03*
X495822D03*
X502582D03*
X509342D03*
X516102D03*
X522861D03*
X529621D03*
X533001Y372197D03*
X539761D03*
X478922D03*
X485682D03*
X492442D03*
X499202D03*
X505962D03*
X512722D03*
X519481D03*
X526241D03*
X536381Y370247D03*
X482302D03*
X489062D03*
X495822D03*
X502582D03*
X509342D03*
X516102D03*
X522861D03*
X529621D03*
X533001Y368296D03*
X539761D03*
X478922D03*
X485682D03*
X492442D03*
X499202D03*
X505962D03*
X512722D03*
X519481D03*
X526241D03*
X536381Y366347D03*
X482302D03*
X489062D03*
X495822D03*
X502582D03*
X509342D03*
X516102D03*
X522861D03*
X529621D03*
X533001Y364396D03*
X539761D03*
X478922D03*
X485682D03*
X492442D03*
X499202D03*
X505962D03*
X512722D03*
X519481D03*
X526241D03*
X536381Y362447D03*
X482302D03*
X489062D03*
X495822D03*
X502582D03*
X509342D03*
X516102D03*
X522861D03*
X529621D03*
X533001Y360496D03*
X539761D03*
X478922D03*
X485682D03*
X492442D03*
X499202D03*
X505962D03*
X512722D03*
X519481D03*
X526241D03*
X536381Y358547D03*
X482302D03*
X489062D03*
X495822D03*
X502582D03*
X509342D03*
X516102D03*
X522861D03*
X529621D03*
X533001Y356596D03*
X539761D03*
X478922D03*
X485682D03*
X492442D03*
X499202D03*
X505962D03*
X512722D03*
X519481D03*
X526241D03*
X536381Y354647D03*
X482302D03*
X489062D03*
X495822D03*
X502582D03*
X509342D03*
X516102D03*
X522861D03*
X529621D03*
X533001Y352696D03*
X539761D03*
X478922D03*
X485682D03*
X492442D03*
X499202D03*
X505962D03*
X519481D03*
X526241D03*
X536381Y350747D03*
X482302D03*
X489062D03*
X495822D03*
X502582D03*
X516102D03*
X522861D03*
X529621D03*
X533001Y348796D03*
X539761D03*
X478922D03*
X485682D03*
X492442D03*
X499202D03*
X519481D03*
X526241D03*
X536381Y346847D03*
X482302D03*
X489062D03*
X495822D03*
X502582D03*
X516102D03*
X522861D03*
X529621D03*
X533001Y344896D03*
X539761D03*
X478922D03*
X485682D03*
X492442D03*
X499202D03*
X519481D03*
X526241D03*
X536381Y342947D03*
X482302D03*
X489062D03*
X495822D03*
X502582D03*
X516102D03*
X522861D03*
X529621D03*
X533001Y379996D03*
X539761D03*
X478922D03*
X485682D03*
X492442D03*
X499202D03*
X505962D03*
X512722D03*
X519481D03*
X526241D03*
X536381Y405347D03*
X482302D03*
X509342D03*
X516102D03*
X522861D03*
X529621D03*
X543141Y218147D03*
X549901D03*
X556661D03*
X546521Y216196D03*
X553281D03*
X560041D03*
X543141Y214247D03*
X549901D03*
X556661D03*
X546521Y212296D03*
X553281D03*
X543141Y210346D03*
X549901D03*
X556661D03*
X546521Y208397D03*
X553281D03*
X543141Y206447D03*
X549901D03*
X546521Y204496D03*
X553281D03*
X543141Y202547D03*
X549901D03*
X546521Y239596D03*
X553281D03*
X560041D03*
X543141Y237647D03*
X549901D03*
X556661D03*
X546521Y235696D03*
X553281D03*
X560041D03*
X543141Y233746D03*
X549901D03*
X556661D03*
X546521Y231797D03*
X553281D03*
X560041D03*
X546521Y227896D03*
X553281D03*
X560041D03*
X543141Y225947D03*
X549901D03*
X556661D03*
X546521Y223996D03*
X553281D03*
X560041D03*
X543141Y222047D03*
X549901D03*
X556661D03*
X546521Y220096D03*
X553281D03*
X560041D03*
X546521Y278596D03*
X553281D03*
X543141Y276646D03*
X549901D03*
X556661D03*
X546521Y274696D03*
X553281D03*
X560041D03*
X543141Y272747D03*
X549901D03*
X556661D03*
X546521Y270796D03*
X553281D03*
X560041D03*
X543141Y268847D03*
X549901D03*
X556661D03*
X546521Y266896D03*
X553281D03*
X560041D03*
X543141Y264947D03*
X549901D03*
X556661D03*
X546521Y262996D03*
X553281D03*
X560041D03*
X543141Y261047D03*
X549901D03*
X556661D03*
X546521Y259096D03*
X553281D03*
X560041D03*
X543141Y257147D03*
X549901D03*
X556661D03*
X546521Y255196D03*
X553281D03*
X560041D03*
X543141Y253247D03*
X549901D03*
X556661D03*
X546521Y251296D03*
X553281D03*
X560041D03*
X543141Y249347D03*
X549901D03*
X556661D03*
X546521Y247396D03*
X553281D03*
X560041D03*
X543141Y245447D03*
X549901D03*
X556661D03*
X546521Y243496D03*
X553281D03*
X560041D03*
X543141Y241547D03*
X549901D03*
X556661D03*
X543141Y229847D03*
X549901D03*
X556661D03*
X546521Y340996D03*
X553281D03*
X560041D03*
X543141Y339047D03*
X549901D03*
X556661D03*
X546521Y337096D03*
X553281D03*
X560041D03*
X543141Y335147D03*
X549901D03*
X556661D03*
X546521Y333196D03*
X553281D03*
X560041D03*
X543141Y331247D03*
X549901D03*
X556661D03*
X546521Y329296D03*
X553281D03*
X543141Y327347D03*
X549901D03*
X556661D03*
X546521Y325396D03*
X553281D03*
X543141Y323446D03*
X549901D03*
X556661D03*
X546521Y321496D03*
X553281D03*
X543141Y319547D03*
X549901D03*
X556661D03*
X546521Y317596D03*
X553281D03*
X543141Y315647D03*
X549901D03*
X546521Y313696D03*
X553281D03*
X543141Y311747D03*
X549901D03*
X546521Y309797D03*
X553281D03*
X543141Y307847D03*
X549901D03*
X546521Y305896D03*
X553281D03*
X543141Y303947D03*
X549901D03*
X546521Y301996D03*
X553281D03*
X543141Y300047D03*
X549901D03*
X546521Y298096D03*
X553281D03*
X543141Y296147D03*
X549901D03*
X546521Y294196D03*
X553281D03*
X543141Y292247D03*
X549901D03*
X546521Y290296D03*
X553281D03*
X543141Y288347D03*
X549901D03*
X546521Y286396D03*
X553281D03*
X543141Y284447D03*
X549901D03*
X556661D03*
X546521Y282496D03*
X553281D03*
X543141Y280547D03*
X549901D03*
X556661D03*
X546521Y403396D03*
X543141Y401447D03*
X549901D03*
X546521Y399496D03*
X553281D03*
X543141Y397546D03*
X549901D03*
X546521Y395597D03*
X553281D03*
X543141Y393647D03*
X549901D03*
X556661D03*
X546521Y391696D03*
X553281D03*
X543141Y389747D03*
X549901D03*
X556661D03*
X546521Y387796D03*
X553281D03*
X543141Y385847D03*
X549901D03*
X556661D03*
X546521Y383896D03*
X553281D03*
X543141Y381947D03*
X549901D03*
X556661D03*
X543141Y378047D03*
X549901D03*
X556661D03*
X546521Y376096D03*
X553281D03*
X543141Y374146D03*
X549901D03*
X556661D03*
X546521Y372197D03*
X553281D03*
X543141Y370247D03*
X549901D03*
X556661D03*
X546521Y368296D03*
X553281D03*
X543141Y366347D03*
X549901D03*
X556661D03*
X546521Y364396D03*
X553281D03*
X543141Y362447D03*
X549901D03*
X556661D03*
X546521Y360496D03*
X553281D03*
X560041D03*
X543141Y358547D03*
X549901D03*
X556661D03*
X546521Y356596D03*
X553281D03*
X560041D03*
X543141Y354647D03*
X549901D03*
X556661D03*
X546521Y352696D03*
X553281D03*
X560041D03*
X543141Y350747D03*
X549901D03*
X556661D03*
X546521Y348796D03*
X553281D03*
X560041D03*
X543141Y346847D03*
X549901D03*
X556661D03*
X546521Y344896D03*
X553281D03*
X560041D03*
X543141Y342947D03*
X549901D03*
X556661D03*
X546521Y379996D03*
X553281D03*
X543141Y405347D03*
X919717Y216909D03*
X926477D03*
X933237D03*
X939997D03*
X946757D03*
X953517D03*
X960276D03*
X967036D03*
X916337Y214960D03*
X923097D03*
X929857D03*
X936617D03*
X943377D03*
X950137D03*
X956897D03*
X963656D03*
X970416D03*
X919717Y213009D03*
X926477D03*
X933237D03*
X939997D03*
X946757D03*
X953517D03*
X960276D03*
X967036D03*
X916337Y211060D03*
X923097D03*
X929857D03*
X936617D03*
X943377D03*
X950137D03*
X956897D03*
X963656D03*
X970416D03*
X919717Y209109D03*
X926477D03*
X933237D03*
X939997D03*
X946757D03*
X953517D03*
X960276D03*
X967036D03*
X923097Y207159D03*
X929857D03*
X936617D03*
X943377D03*
X950137D03*
X956897D03*
X963656D03*
X970416D03*
X926477Y205210D03*
X933237D03*
X939997D03*
X946757D03*
X953517D03*
X960276D03*
X967036D03*
X923097Y203260D03*
X929857D03*
X936617D03*
X943377D03*
X950137D03*
X956897D03*
X963656D03*
X926477Y201309D03*
X933237D03*
X939997D03*
X946757D03*
X953517D03*
X960276D03*
X967036D03*
X929857Y199360D03*
X936617D03*
X943377D03*
X950137D03*
X956897D03*
X963656D03*
X933237Y197409D03*
X939997D03*
X946757D03*
X953517D03*
X960276D03*
X967036D03*
X919717Y232509D03*
X926477D03*
X933237D03*
X939997D03*
X946757D03*
X953517D03*
X960276D03*
X967036D03*
X916337Y230559D03*
X923097D03*
X929857D03*
X936617D03*
X943377D03*
X950137D03*
X956897D03*
X963656D03*
X970416D03*
X919717Y228610D03*
X926477D03*
X933237D03*
X939997D03*
X946757D03*
X953517D03*
X960276D03*
X967036D03*
X916337Y226660D03*
X923097D03*
X929857D03*
X936617D03*
X943377D03*
X950137D03*
X956897D03*
X963656D03*
X970416D03*
X919717Y224709D03*
X926477D03*
X933237D03*
X939997D03*
X946757D03*
X953517D03*
X960276D03*
X967036D03*
X919717Y220809D03*
X926477D03*
X933237D03*
X939997D03*
X946757D03*
X953517D03*
X960276D03*
X967036D03*
X916337Y218860D03*
X923097D03*
X929857D03*
X936617D03*
X943377D03*
X950137D03*
X956897D03*
X963656D03*
X970416D03*
X919717Y279310D03*
X926477D03*
X933237D03*
X939997D03*
X946757D03*
X953517D03*
X960276D03*
X967036D03*
X923097Y277360D03*
X929857D03*
X936617D03*
X943377D03*
X950137D03*
X956897D03*
X963656D03*
X970416D03*
X919717Y275409D03*
X926477D03*
X933237D03*
X939997D03*
X946757D03*
X953517D03*
X960276D03*
X967036D03*
X916337Y273460D03*
X923097D03*
X929857D03*
X936617D03*
X943377D03*
X950137D03*
X956897D03*
X963656D03*
X970416D03*
X919717Y271509D03*
X926477D03*
X933237D03*
X939997D03*
X946757D03*
X953517D03*
X960276D03*
X967036D03*
X916337Y269560D03*
X923097D03*
X929857D03*
X936617D03*
X943377D03*
X950137D03*
X956897D03*
X963656D03*
X970416D03*
X919717Y267609D03*
X926477D03*
X933237D03*
X939997D03*
X946757D03*
X953517D03*
X960276D03*
X967036D03*
X916337Y265660D03*
X923097D03*
X929857D03*
X936617D03*
X943377D03*
X950137D03*
X956897D03*
X963656D03*
X970416D03*
X919717Y263709D03*
X926477D03*
X933237D03*
X939997D03*
X946757D03*
X953517D03*
X960276D03*
X967036D03*
X916337Y261760D03*
X923097D03*
X929857D03*
X936617D03*
X943377D03*
X950137D03*
X956897D03*
X963656D03*
X919717Y259809D03*
X926477D03*
X933237D03*
X939997D03*
X946757D03*
X953517D03*
X960276D03*
X916337Y257860D03*
X923097D03*
X929857D03*
X936617D03*
X943377D03*
X950137D03*
X956897D03*
X919717Y255909D03*
X926477D03*
X933237D03*
X939997D03*
X946757D03*
X953517D03*
X960276D03*
X916337Y253960D03*
X923097D03*
X929857D03*
X936617D03*
X943377D03*
X950137D03*
X956897D03*
X919717Y252009D03*
X926477D03*
X933237D03*
X939997D03*
X946757D03*
X953517D03*
X960276D03*
X916337Y250060D03*
X923097D03*
X929857D03*
X936617D03*
X943377D03*
X950137D03*
X956897D03*
X970416D03*
X919717Y248109D03*
X926477D03*
X933237D03*
X939997D03*
X946757D03*
X953517D03*
X960276D03*
X967036D03*
X916337Y246160D03*
X923097D03*
X929857D03*
X936617D03*
X943377D03*
X950137D03*
X956897D03*
X963656D03*
X970416D03*
X919717Y244209D03*
X926477D03*
X933237D03*
X939997D03*
X946757D03*
X953517D03*
X960276D03*
X967036D03*
X916337Y242260D03*
X923097D03*
X929857D03*
X936617D03*
X943377D03*
X950137D03*
X956897D03*
X963656D03*
X970416D03*
X919717Y240309D03*
X926477D03*
X933237D03*
X939997D03*
X946757D03*
X953517D03*
X960276D03*
X967036D03*
X916337Y238360D03*
X923097D03*
X929857D03*
X936617D03*
X943377D03*
X950137D03*
X956897D03*
X963656D03*
X970416D03*
X919717Y236409D03*
X926477D03*
X933237D03*
X939997D03*
X946757D03*
X953517D03*
X960276D03*
X967036D03*
X916337Y234460D03*
X923097D03*
X929857D03*
X936617D03*
X943377D03*
X950137D03*
X956897D03*
X963656D03*
X970416D03*
X916337Y222760D03*
X923097D03*
X929857D03*
X936617D03*
X943377D03*
X950137D03*
X956897D03*
X963656D03*
X970416D03*
X919717Y341709D03*
X926477D03*
X933237D03*
X939997D03*
X946757D03*
X953517D03*
X960276D03*
X916337Y339760D03*
X923097D03*
X929857D03*
X936617D03*
X943377D03*
X950137D03*
X956897D03*
X919717Y337809D03*
X926477D03*
X933237D03*
X939997D03*
X946757D03*
X953517D03*
X960276D03*
X916337Y335860D03*
X923097D03*
X929857D03*
X936617D03*
X943377D03*
X950137D03*
X956897D03*
X970416D03*
X919717Y333909D03*
X926477D03*
X933237D03*
X939997D03*
X946757D03*
X953517D03*
X960276D03*
X967036D03*
X916337Y331960D03*
X923097D03*
X929857D03*
X936617D03*
X943377D03*
X950137D03*
X956897D03*
X963656D03*
X970416D03*
X919717Y330009D03*
X926477D03*
X933237D03*
X939997D03*
X946757D03*
X953517D03*
X960276D03*
X967036D03*
X916337Y328060D03*
X923097D03*
X929857D03*
X936617D03*
X943377D03*
X950137D03*
X956897D03*
X963656D03*
X970416D03*
X919717Y326110D03*
X926477D03*
X933237D03*
X939997D03*
X946757D03*
X953517D03*
X960276D03*
X967036D03*
X923097Y324160D03*
X929857D03*
X936617D03*
X943377D03*
X950137D03*
X956897D03*
X963656D03*
X970416D03*
X919717Y322209D03*
X926477D03*
X933237D03*
X939997D03*
X946757D03*
X953517D03*
X960276D03*
X967036D03*
X923097Y320260D03*
X929857D03*
X936617D03*
X943377D03*
X950137D03*
X956897D03*
X963656D03*
X970416D03*
X919717Y318309D03*
X926477D03*
X933237D03*
X939997D03*
X946757D03*
X953517D03*
X960276D03*
X967036D03*
X923097Y316360D03*
X929857D03*
X936617D03*
X943377D03*
X950137D03*
X956897D03*
X963656D03*
X970416D03*
X926477Y314409D03*
X933237D03*
X939997D03*
X946757D03*
X953517D03*
X960276D03*
X967036D03*
X923097Y312460D03*
X929857D03*
X936617D03*
X943377D03*
X950137D03*
X956897D03*
X963656D03*
X970416D03*
X926477Y310509D03*
X933237D03*
X939997D03*
X946757D03*
X953517D03*
X960276D03*
X967036D03*
X923097Y308560D03*
X929857D03*
X936617D03*
X943377D03*
X950137D03*
X956897D03*
X963656D03*
X970416D03*
X926477Y306609D03*
X933237D03*
X939997D03*
X946757D03*
X953517D03*
X960276D03*
X967036D03*
X923097Y304660D03*
X929857D03*
X936617D03*
X943377D03*
X950137D03*
X956897D03*
X963656D03*
X970416D03*
X926477Y302709D03*
X933237D03*
X939997D03*
X946757D03*
X953517D03*
X960276D03*
X967036D03*
X923097Y300760D03*
X929857D03*
X936617D03*
X943377D03*
X950137D03*
X956897D03*
X963656D03*
X970416D03*
X926477Y298809D03*
X933237D03*
X939997D03*
X946757D03*
X953517D03*
X960276D03*
X967036D03*
X923097Y296860D03*
X929857D03*
X936617D03*
X943377D03*
X950137D03*
X956897D03*
X963656D03*
X970416D03*
X926477Y294909D03*
X933237D03*
X939997D03*
X946757D03*
X953517D03*
X960276D03*
X967036D03*
X923097Y292959D03*
X929857D03*
X936617D03*
X943377D03*
X950137D03*
X956897D03*
X963656D03*
X970416D03*
X926477Y291009D03*
X933237D03*
X939997D03*
X946757D03*
X953517D03*
X960276D03*
X967036D03*
X923097Y289060D03*
X929857D03*
X936617D03*
X943377D03*
X950137D03*
X956897D03*
X963656D03*
X970416D03*
X926477Y287109D03*
X933237D03*
X939997D03*
X946757D03*
X953517D03*
X960276D03*
X967036D03*
X923097Y285160D03*
X929857D03*
X936617D03*
X943377D03*
X950137D03*
X956897D03*
X963656D03*
X970416D03*
X919717Y283209D03*
X926477D03*
X933237D03*
X939997D03*
X946757D03*
X953517D03*
X960276D03*
X967036D03*
X923097Y281260D03*
X929857D03*
X936617D03*
X943377D03*
X950137D03*
X956897D03*
X963656D03*
X970416D03*
X926477Y400209D03*
X933237D03*
X939997D03*
X946757D03*
X953517D03*
X960276D03*
X967036D03*
X923097Y398260D03*
X929857D03*
X936617D03*
X943377D03*
X950137D03*
X956897D03*
X963656D03*
X970416D03*
X926477Y396309D03*
X933237D03*
X939997D03*
X946757D03*
X953517D03*
X960276D03*
X967036D03*
X923097Y394359D03*
X929857D03*
X936617D03*
X943377D03*
X950137D03*
X956897D03*
X963656D03*
X970416D03*
X919717Y392410D03*
X926477D03*
X933237D03*
X939997D03*
X946757D03*
X953517D03*
X960276D03*
X967036D03*
X923097Y390460D03*
X929857D03*
X936617D03*
X943377D03*
X950137D03*
X956897D03*
X963656D03*
X970416D03*
X919717Y388509D03*
X926477D03*
X933237D03*
X939997D03*
X946757D03*
X953517D03*
X960276D03*
X967036D03*
X923097Y386560D03*
X929857D03*
X936617D03*
X943377D03*
X950137D03*
X956897D03*
X963656D03*
X970416D03*
X919717Y384609D03*
X926477D03*
X933237D03*
X939997D03*
X946757D03*
X953517D03*
X960276D03*
X967036D03*
X923097Y382660D03*
X929857D03*
X936617D03*
X943377D03*
X950137D03*
X956897D03*
X963656D03*
X970416D03*
X919717Y380709D03*
X926477D03*
X933237D03*
X939997D03*
X946757D03*
X953517D03*
X960276D03*
X967036D03*
X923097Y378760D03*
X929857D03*
X936617D03*
X943377D03*
X950137D03*
X956897D03*
X963656D03*
X970416D03*
X919717Y376809D03*
X926477D03*
X933237D03*
X939997D03*
X946757D03*
X953517D03*
X960276D03*
X967036D03*
X923097Y374860D03*
X929857D03*
X936617D03*
X943377D03*
X950137D03*
X956897D03*
X963656D03*
X970416D03*
X923097Y370959D03*
X929857D03*
X936617D03*
X943377D03*
X950137D03*
X956897D03*
X963656D03*
X970416D03*
X919717Y369010D03*
X926477D03*
X933237D03*
X939997D03*
X946757D03*
X953517D03*
X960276D03*
X967036D03*
X923097Y367060D03*
X929857D03*
X936617D03*
X943377D03*
X950137D03*
X956897D03*
X963656D03*
X970416D03*
X919717Y365109D03*
X926477D03*
X933237D03*
X939997D03*
X946757D03*
X953517D03*
X960276D03*
X967036D03*
X923097Y363160D03*
X929857D03*
X936617D03*
X943377D03*
X950137D03*
X956897D03*
X963656D03*
X970416D03*
X919717Y361209D03*
X926477D03*
X933237D03*
X939997D03*
X946757D03*
X953517D03*
X960276D03*
X967036D03*
X923097Y359260D03*
X929857D03*
X936617D03*
X943377D03*
X950137D03*
X956897D03*
X963656D03*
X970416D03*
X919717Y357309D03*
X926477D03*
X933237D03*
X939997D03*
X946757D03*
X953517D03*
X960276D03*
X967036D03*
X916337Y355360D03*
X923097D03*
X929857D03*
X936617D03*
X943377D03*
X950137D03*
X956897D03*
X963656D03*
X970416D03*
X919717Y353409D03*
X926477D03*
X933237D03*
X939997D03*
X946757D03*
X953517D03*
X960276D03*
X967036D03*
X916337Y351460D03*
X923097D03*
X929857D03*
X936617D03*
X943377D03*
X950137D03*
X956897D03*
X963656D03*
X970416D03*
X919717Y349509D03*
X926477D03*
X933237D03*
X939997D03*
X946757D03*
X953517D03*
X960276D03*
X967036D03*
X916337Y347560D03*
X923097D03*
X929857D03*
X936617D03*
X943377D03*
X950137D03*
X956897D03*
X963656D03*
X919717Y345609D03*
X926477D03*
X933237D03*
X939997D03*
X946757D03*
X953517D03*
X960276D03*
X916337Y343660D03*
X923097D03*
X929857D03*
X936617D03*
X943377D03*
X950137D03*
X956897D03*
X919717Y372909D03*
X926477D03*
X933237D03*
X939997D03*
X946757D03*
X953517D03*
X960276D03*
X967036D03*
X973796Y216909D03*
X980556D03*
X987316D03*
X994076D03*
X1000836D03*
X1007595D03*
X1014355D03*
X1021115D03*
X1027875D03*
X977176Y214960D03*
X983936D03*
X990696D03*
X997456D03*
X1004215D03*
X1010975D03*
X1017735D03*
X1024495D03*
X1031255D03*
X973796Y213009D03*
X980556D03*
X987316D03*
X994076D03*
X1000836D03*
X1007595D03*
X1014355D03*
X1021115D03*
X1027875D03*
X977176Y211060D03*
X983936D03*
X990696D03*
X997456D03*
X1004215D03*
X1010975D03*
X1017735D03*
X1024495D03*
X1031255D03*
X973796Y209109D03*
X980556D03*
X987316D03*
X994076D03*
X1000836D03*
X1007595D03*
X1014355D03*
X1021115D03*
X1027875D03*
X977176Y207159D03*
X983936D03*
X990696D03*
X997456D03*
X1004215D03*
X1010975D03*
X1017735D03*
X1024495D03*
X1031255D03*
X973796Y205210D03*
X980556D03*
X987316D03*
X994076D03*
X1000836D03*
X1007595D03*
X1014355D03*
X1021115D03*
X1027875D03*
X983936Y203260D03*
X990696D03*
X997456D03*
X1004215D03*
X1010975D03*
X1017735D03*
X1024495D03*
X1031255D03*
X987316Y201309D03*
X994076D03*
X1000836D03*
X1007595D03*
X1014355D03*
X1021115D03*
X1027875D03*
X990696Y199360D03*
X997456D03*
X1004215D03*
X1010975D03*
X1017735D03*
X1024495D03*
X1031255D03*
X994076Y197409D03*
X1000836D03*
X1007595D03*
X1014355D03*
X1021115D03*
X1027875D03*
X973796Y232509D03*
X980556D03*
X987316D03*
X994076D03*
X1000836D03*
X1007595D03*
X1014355D03*
X1021115D03*
X1027875D03*
X977176Y230559D03*
X983936D03*
X990696D03*
X997456D03*
X1004215D03*
X1010975D03*
X1017735D03*
X1024495D03*
X1031255D03*
X973796Y228610D03*
X980556D03*
X987316D03*
X994076D03*
X1000836D03*
X1007595D03*
X1014355D03*
X1021115D03*
X1027875D03*
X977176Y226660D03*
X983936D03*
X990696D03*
X997456D03*
X1004215D03*
X1010975D03*
X1017735D03*
X1024495D03*
X1031255D03*
X973796Y224709D03*
X980556D03*
X987316D03*
X994076D03*
X1000836D03*
X1007595D03*
X1014355D03*
X1021115D03*
X1027875D03*
X973796Y220809D03*
X980556D03*
X987316D03*
X994076D03*
X1000836D03*
X1007595D03*
X1014355D03*
X1021115D03*
X1027875D03*
X977176Y218860D03*
X983936D03*
X990696D03*
X997456D03*
X1004215D03*
X1010975D03*
X1017735D03*
X1024495D03*
X1031255D03*
X973796Y279310D03*
X980556D03*
X987316D03*
X994076D03*
X1000836D03*
X977176Y277360D03*
X983936D03*
X990696D03*
X997456D03*
X973796Y275409D03*
X980556D03*
X987316D03*
X994076D03*
X1000836D03*
X977176Y273460D03*
X983936D03*
X990696D03*
X997456D03*
X973796Y271509D03*
X980556D03*
X987316D03*
X994076D03*
X1000836D03*
X977176Y269560D03*
X983936D03*
X990696D03*
X997456D03*
X973796Y267609D03*
X980556D03*
X987316D03*
X994076D03*
X1000836D03*
X977176Y265660D03*
X983936D03*
X990696D03*
X997456D03*
X1004215D03*
X973796Y263709D03*
X980556D03*
X987316D03*
X994076D03*
X1000836D03*
X1007595D03*
X977176Y261760D03*
X983936D03*
X990696D03*
X997456D03*
X1004215D03*
X1010975D03*
X973796Y259809D03*
X980556D03*
X987316D03*
X994076D03*
X1000836D03*
X1007595D03*
X1014355D03*
X977176Y257860D03*
X983936D03*
X990696D03*
X997456D03*
X1004215D03*
X1010975D03*
X1017735D03*
X973796Y255909D03*
X980556D03*
X987316D03*
X994076D03*
X1000836D03*
X1007595D03*
X1014355D03*
X1021115D03*
X977176Y253960D03*
X983936D03*
X990696D03*
X997456D03*
X1004215D03*
X1010975D03*
X1017735D03*
X1024495D03*
X973796Y252009D03*
X980556D03*
X987316D03*
X994076D03*
X1000836D03*
X1007595D03*
X1014355D03*
X1021115D03*
X1027875D03*
X977176Y250060D03*
X983936D03*
X990696D03*
X997456D03*
X1004215D03*
X1010975D03*
X1017735D03*
X1024495D03*
X1031255D03*
X973796Y248109D03*
X980556D03*
X987316D03*
X994076D03*
X1000836D03*
X1007595D03*
X1014355D03*
X1021115D03*
X1027875D03*
X977176Y246160D03*
X983936D03*
X990696D03*
X997456D03*
X1004215D03*
X1010975D03*
X1017735D03*
X1024495D03*
X1031255D03*
X973796Y244209D03*
X980556D03*
X987316D03*
X994076D03*
X1000836D03*
X1007595D03*
X1014355D03*
X1021115D03*
X1027875D03*
X977176Y242260D03*
X983936D03*
X990696D03*
X997456D03*
X1004215D03*
X1010975D03*
X1017735D03*
X1024495D03*
X1031255D03*
X973796Y240309D03*
X980556D03*
X987316D03*
X994076D03*
X1000836D03*
X1007595D03*
X1014355D03*
X1021115D03*
X1027875D03*
X977176Y238360D03*
X983936D03*
X990696D03*
X997456D03*
X1004215D03*
X1010975D03*
X1017735D03*
X1024495D03*
X1031255D03*
X973796Y236409D03*
X980556D03*
X987316D03*
X994076D03*
X1000836D03*
X1007595D03*
X1014355D03*
X1021115D03*
X1027875D03*
X977176Y234460D03*
X983936D03*
X990696D03*
X997456D03*
X1004215D03*
X1010975D03*
X1017735D03*
X1024495D03*
X1031255D03*
X977176Y222760D03*
X983936D03*
X990696D03*
X997456D03*
X1004215D03*
X1010975D03*
X1017735D03*
X1024495D03*
X1031255D03*
X973796Y341709D03*
X980556D03*
X987316D03*
X994076D03*
X1000836D03*
X1007595D03*
X1014355D03*
X1021115D03*
X977176Y339760D03*
X983936D03*
X990696D03*
X997456D03*
X1004215D03*
X1010975D03*
X1017735D03*
X973796Y337809D03*
X980556D03*
X987316D03*
X994076D03*
X1000836D03*
X1007595D03*
X1014355D03*
X977176Y335860D03*
X983936D03*
X990696D03*
X997456D03*
X1004215D03*
X1010975D03*
X973796Y333909D03*
X980556D03*
X987316D03*
X994076D03*
X1000836D03*
X1007595D03*
X977176Y331960D03*
X983936D03*
X990696D03*
X997456D03*
X1004215D03*
X973796Y330009D03*
X980556D03*
X987316D03*
X994076D03*
X1000836D03*
X977176Y328060D03*
X983936D03*
X990696D03*
X997456D03*
X973796Y326110D03*
X980556D03*
X987316D03*
X994076D03*
X1000836D03*
X977176Y324160D03*
X983936D03*
X990696D03*
X997456D03*
X973796Y322209D03*
X980556D03*
X987316D03*
X994076D03*
X1000836D03*
X977176Y320260D03*
X983936D03*
X990696D03*
X997456D03*
X973796Y318309D03*
X980556D03*
X987316D03*
X994076D03*
X1000836D03*
X977176Y316360D03*
X983936D03*
X990696D03*
X997456D03*
X973796Y314409D03*
X980556D03*
X987316D03*
X994076D03*
X1000836D03*
X977176Y312460D03*
X983936D03*
X990696D03*
X997456D03*
X973796Y310509D03*
X980556D03*
X987316D03*
X994076D03*
X1000836D03*
X977176Y308560D03*
X983936D03*
X990696D03*
X997456D03*
X973796Y306609D03*
X980556D03*
X987316D03*
X994076D03*
X1000836D03*
X977176Y304660D03*
X983936D03*
X990696D03*
X997456D03*
X973796Y302709D03*
X980556D03*
X987316D03*
X994076D03*
X1000836D03*
X977176Y300760D03*
X983936D03*
X990696D03*
X997456D03*
X973796Y298809D03*
X980556D03*
X987316D03*
X994076D03*
X1000836D03*
X977176Y296860D03*
X983936D03*
X990696D03*
X997456D03*
X973796Y294909D03*
X980556D03*
X987316D03*
X994076D03*
X1000836D03*
X977176Y292959D03*
X983936D03*
X990696D03*
X997456D03*
X973796Y291009D03*
X980556D03*
X987316D03*
X994076D03*
X1000836D03*
X977176Y289060D03*
X983936D03*
X990696D03*
X997456D03*
X973796Y287109D03*
X980556D03*
X987316D03*
X994076D03*
X1000836D03*
X977176Y285160D03*
X983936D03*
X990696D03*
X997456D03*
X973796Y283209D03*
X980556D03*
X987316D03*
X994076D03*
X1000836D03*
X977176Y281260D03*
X983936D03*
X990696D03*
X997456D03*
X994076Y400209D03*
X1000836D03*
X1007595D03*
X1014355D03*
X1021115D03*
X1027875D03*
X997456Y398260D03*
X1004215D03*
X1010975D03*
X1017735D03*
X1024495D03*
X1031255D03*
X973796Y396309D03*
X994076D03*
X1000836D03*
X1007595D03*
X1014355D03*
X1021115D03*
X1027875D03*
X997456Y394359D03*
X1004215D03*
X1010975D03*
X1017735D03*
X1024495D03*
X1031255D03*
X973796Y392410D03*
X980556D03*
X987316D03*
X994076D03*
X1000836D03*
X1007595D03*
X1014355D03*
X1021115D03*
X1027875D03*
X977176Y390460D03*
X983936D03*
X990696D03*
X997456D03*
X1004215D03*
X1010975D03*
X1017735D03*
X1024495D03*
X1031255D03*
X973796Y388509D03*
X980556D03*
X987316D03*
X994076D03*
X1000836D03*
X1007595D03*
X1014355D03*
X1021115D03*
X1027875D03*
X977176Y386560D03*
X983936D03*
X990696D03*
X997456D03*
X1004215D03*
X1010975D03*
X1017735D03*
X1024495D03*
X1031255D03*
X973796Y384609D03*
X980556D03*
X987316D03*
X994076D03*
X1000836D03*
X1007595D03*
X1014355D03*
X1021115D03*
X1027875D03*
X977176Y382660D03*
X983936D03*
X990696D03*
X997456D03*
X1004215D03*
X1010975D03*
X1017735D03*
X1024495D03*
X1031255D03*
X973796Y380709D03*
X980556D03*
X987316D03*
X994076D03*
X1000836D03*
X1007595D03*
X1014355D03*
X1021115D03*
X1027875D03*
X977176Y378760D03*
X983936D03*
X990696D03*
X997456D03*
X1004215D03*
X1010975D03*
X1017735D03*
X1024495D03*
X1031255D03*
X973796Y376809D03*
X980556D03*
X987316D03*
X994076D03*
X1000836D03*
X1007595D03*
X1014355D03*
X1021115D03*
X1027875D03*
X977176Y374860D03*
X983936D03*
X990696D03*
X997456D03*
X1004215D03*
X1010975D03*
X1017735D03*
X1024495D03*
X1031255D03*
X977176Y370959D03*
X983936D03*
X990696D03*
X997456D03*
X1004215D03*
X1010975D03*
X1017735D03*
X1024495D03*
X1031255D03*
X973796Y369010D03*
X980556D03*
X987316D03*
X994076D03*
X1000836D03*
X1007595D03*
X1014355D03*
X1021115D03*
X1027875D03*
X977176Y367060D03*
X983936D03*
X990696D03*
X997456D03*
X1004215D03*
X1010975D03*
X1017735D03*
X1024495D03*
X1031255D03*
X973796Y365109D03*
X980556D03*
X987316D03*
X994076D03*
X1000836D03*
X1007595D03*
X1014355D03*
X1021115D03*
X1027875D03*
X977176Y363160D03*
X983936D03*
X990696D03*
X997456D03*
X1004215D03*
X1010975D03*
X1017735D03*
X1024495D03*
X1031255D03*
X973796Y361209D03*
X980556D03*
X987316D03*
X994076D03*
X1000836D03*
X1007595D03*
X1014355D03*
X1021115D03*
X1027875D03*
X977176Y359260D03*
X983936D03*
X990696D03*
X997456D03*
X1004215D03*
X1010975D03*
X1017735D03*
X1024495D03*
X1031255D03*
X973796Y357309D03*
X980556D03*
X987316D03*
X994076D03*
X1000836D03*
X1007595D03*
X1014355D03*
X1021115D03*
X1027875D03*
X977176Y355360D03*
X983936D03*
X990696D03*
X997456D03*
X1004215D03*
X1010975D03*
X1017735D03*
X1024495D03*
X1031255D03*
X973796Y353409D03*
X980556D03*
X987316D03*
X994076D03*
X1000836D03*
X1007595D03*
X1014355D03*
X1021115D03*
X1027875D03*
X977176Y351460D03*
X983936D03*
X990696D03*
X997456D03*
X1004215D03*
X1010975D03*
X1017735D03*
X1024495D03*
X1031255D03*
X973796Y349509D03*
X980556D03*
X987316D03*
X994076D03*
X1000836D03*
X1007595D03*
X1014355D03*
X1021115D03*
X1027875D03*
X977176Y347560D03*
X983936D03*
X990696D03*
X997456D03*
X1004215D03*
X1010975D03*
X1017735D03*
X1024495D03*
X1031255D03*
X973796Y345609D03*
X980556D03*
X987316D03*
X994076D03*
X1000836D03*
X1007595D03*
X1014355D03*
X1021115D03*
X1027875D03*
X977176Y343660D03*
X983936D03*
X990696D03*
X997456D03*
X1004215D03*
X1010975D03*
X1017735D03*
X1024495D03*
X973796Y372909D03*
X980556D03*
X987316D03*
X994076D03*
X1000836D03*
X1007595D03*
X1014355D03*
X1021115D03*
X1027875D03*
X1034635Y216909D03*
X1041395D03*
X1048154D03*
X1038015Y214960D03*
X1044774D03*
X1051534D03*
X1034635Y213009D03*
X1041395D03*
X1048154D03*
X1038015Y211060D03*
X1044774D03*
X1051534D03*
X1071072Y218147D03*
X1077832D03*
X1084591D03*
X1091351D03*
X1034635Y209109D03*
X1041395D03*
X1048154D03*
X1067692Y216196D03*
X1074452D03*
X1081212D03*
X1087971D03*
X1094731D03*
X1038015Y207159D03*
X1044774D03*
X1051534D03*
X1071072Y214247D03*
X1077832D03*
X1084591D03*
X1091351D03*
X1034635Y205210D03*
X1041395D03*
X1048154D03*
X1067692Y212296D03*
X1074452D03*
X1081212D03*
X1087971D03*
X1094731D03*
X1038015Y203260D03*
X1044774D03*
X1051534D03*
X1071072Y210346D03*
X1077832D03*
X1084591D03*
X1091351D03*
X1034635Y201309D03*
X1041395D03*
X1048154D03*
X1054914D03*
X1067692Y208397D03*
X1074452D03*
X1081212D03*
X1087971D03*
X1094731D03*
X1038015Y199360D03*
X1044774D03*
X1051534D03*
X1071072Y206447D03*
X1077832D03*
X1084591D03*
X1091351D03*
X1034635Y197409D03*
X1041395D03*
X1048154D03*
X1067692Y204496D03*
X1074452D03*
X1081212D03*
X1087971D03*
X1094731D03*
X1071072Y202547D03*
X1077832D03*
X1084591D03*
X1091351D03*
X1034635Y232509D03*
X1041395D03*
X1048154D03*
X1067692Y239596D03*
X1074452D03*
X1081212D03*
X1087971D03*
X1094731D03*
X1038015Y230559D03*
X1044774D03*
X1051534D03*
X1071072Y237647D03*
X1077832D03*
X1084591D03*
X1091351D03*
X1034635Y228610D03*
X1041395D03*
X1048154D03*
X1067692Y235696D03*
X1074452D03*
X1081212D03*
X1087971D03*
X1094731D03*
X1038015Y226660D03*
X1044774D03*
X1051534D03*
X1071072Y233746D03*
X1077832D03*
X1084591D03*
X1091351D03*
X1034635Y224709D03*
X1041395D03*
X1048154D03*
X1067692Y231797D03*
X1074452D03*
X1081212D03*
X1087971D03*
X1094731D03*
X1034635Y220809D03*
X1041395D03*
X1048154D03*
X1067692Y227896D03*
X1074452D03*
X1081212D03*
X1087971D03*
X1094731D03*
X1038015Y218860D03*
X1044774D03*
X1051534D03*
X1071072Y225947D03*
X1077832D03*
X1084591D03*
X1091351D03*
X1067692Y223996D03*
X1074452D03*
X1081212D03*
X1087971D03*
X1094731D03*
X1071072Y222047D03*
X1077832D03*
X1084591D03*
X1091351D03*
X1067692Y220096D03*
X1074452D03*
X1081212D03*
X1087971D03*
X1094731D03*
X1034635Y252009D03*
X1041395D03*
X1048154D03*
X1094731Y259096D03*
X1038015Y250060D03*
X1044774D03*
X1051534D03*
X1091351Y257147D03*
X1034635Y248109D03*
X1041395D03*
X1048154D03*
X1074452Y255196D03*
X1081212D03*
X1087971D03*
X1094731D03*
X1038015Y246160D03*
X1044774D03*
X1051534D03*
X1071072Y253247D03*
X1077832D03*
X1084591D03*
X1091351D03*
X1034635Y244209D03*
X1041395D03*
X1048154D03*
X1067692Y251296D03*
X1074452D03*
X1081212D03*
X1087971D03*
X1094731D03*
X1038015Y242260D03*
X1044774D03*
X1051534D03*
X1071072Y249347D03*
X1077832D03*
X1084591D03*
X1091351D03*
X1034635Y240309D03*
X1041395D03*
X1048154D03*
X1067692Y247396D03*
X1074452D03*
X1081212D03*
X1087971D03*
X1094731D03*
X1038015Y238360D03*
X1044774D03*
X1051534D03*
X1071072Y245447D03*
X1077832D03*
X1084591D03*
X1091351D03*
X1034635Y236409D03*
X1041395D03*
X1048154D03*
X1067692Y243496D03*
X1074452D03*
X1081212D03*
X1087971D03*
X1094731D03*
X1038015Y234460D03*
X1044774D03*
X1051534D03*
X1071072Y241547D03*
X1077832D03*
X1084591D03*
X1091351D03*
X1038015Y222760D03*
X1044774D03*
X1051534D03*
X1071072Y229847D03*
X1077832D03*
X1084591D03*
X1091351D03*
X1034635Y400209D03*
X1041395D03*
X1048154D03*
X1054914D03*
X1038015Y398260D03*
X1044774D03*
X1051534D03*
X1058294D03*
X1034635Y396309D03*
X1041395D03*
X1048154D03*
X1054914D03*
X1074452Y403396D03*
X1081212D03*
X1087971D03*
X1094731D03*
X1038015Y394359D03*
X1044774D03*
X1051534D03*
X1071072Y401447D03*
X1077832D03*
X1084591D03*
X1091351D03*
X1034635Y392410D03*
X1041395D03*
X1048154D03*
X1054914D03*
X1074452Y399496D03*
X1081212D03*
X1087971D03*
X1094731D03*
X1038015Y390460D03*
X1044774D03*
X1051534D03*
X1071072Y397546D03*
X1077832D03*
X1084591D03*
X1091351D03*
X1034635Y388509D03*
X1041395D03*
X1048154D03*
X1054914D03*
X1074452Y395597D03*
X1081212D03*
X1087971D03*
X1094731D03*
X1038015Y386560D03*
X1044774D03*
X1051534D03*
X1071072Y393647D03*
X1077832D03*
X1084591D03*
X1091351D03*
X1034635Y384609D03*
X1041395D03*
X1048154D03*
X1054914D03*
X1074452Y391696D03*
X1081212D03*
X1087971D03*
X1094731D03*
X1038015Y382660D03*
X1044774D03*
X1051534D03*
X1071072Y389747D03*
X1077832D03*
X1084591D03*
X1091351D03*
X1034635Y380709D03*
X1041395D03*
X1048154D03*
X1054914D03*
X1074452Y387796D03*
X1081212D03*
X1087971D03*
X1094731D03*
X1038015Y378760D03*
X1044774D03*
X1051534D03*
X1071072Y385847D03*
X1077832D03*
X1084591D03*
X1091351D03*
X1034635Y376809D03*
X1041395D03*
X1048154D03*
X1054914D03*
X1074452Y383896D03*
X1081212D03*
X1087971D03*
X1094731D03*
X1038015Y374860D03*
X1044774D03*
X1051534D03*
X1071072Y381947D03*
X1077832D03*
X1084591D03*
X1091351D03*
X1038015Y370959D03*
X1044774D03*
X1051534D03*
X1071072Y378047D03*
X1077832D03*
X1084591D03*
X1091351D03*
X1034635Y369010D03*
X1041395D03*
X1048154D03*
X1054914D03*
X1074452Y376096D03*
X1081212D03*
X1087971D03*
X1094731D03*
X1038015Y367060D03*
X1044774D03*
X1051534D03*
X1071072Y374146D03*
X1077832D03*
X1084591D03*
X1091351D03*
X1034635Y365109D03*
X1041395D03*
X1048154D03*
X1054914D03*
X1074452Y372197D03*
X1081212D03*
X1087971D03*
X1094731D03*
X1038015Y363160D03*
X1044774D03*
X1051534D03*
X1071072Y370247D03*
X1077832D03*
X1084591D03*
X1091351D03*
X1034635Y361209D03*
X1041395D03*
X1048154D03*
X1054914D03*
X1074452Y368296D03*
X1081212D03*
X1087971D03*
X1094731D03*
X1038015Y359260D03*
X1044774D03*
X1051534D03*
X1071072Y366347D03*
X1077832D03*
X1084591D03*
X1091351D03*
X1034635Y357309D03*
X1041395D03*
X1048154D03*
X1054914D03*
X1074452Y364396D03*
X1081212D03*
X1087971D03*
X1094731D03*
X1038015Y355360D03*
X1044774D03*
X1051534D03*
X1071072Y362447D03*
X1077832D03*
X1084591D03*
X1091351D03*
X1034635Y353409D03*
X1041395D03*
X1048154D03*
X1054914D03*
X1074452Y360496D03*
X1081212D03*
X1087971D03*
X1094731D03*
X1038015Y351460D03*
X1044774D03*
X1051534D03*
X1071072Y358547D03*
X1077832D03*
X1084591D03*
X1091351D03*
X1034635Y349509D03*
X1041395D03*
X1048154D03*
X1074452Y356596D03*
X1081212D03*
X1087971D03*
X1094731D03*
X1071072Y354647D03*
X1077832D03*
X1084591D03*
X1091351D03*
X1074452Y352696D03*
X1081212D03*
X1087971D03*
X1094731D03*
X1071072Y350747D03*
X1077832D03*
X1084591D03*
X1091351D03*
X1074452Y348796D03*
X1081212D03*
X1087971D03*
X1094731D03*
X1034635Y372909D03*
X1041395D03*
X1048154D03*
X1054914D03*
X1074452Y379996D03*
X1081212D03*
X1087971D03*
X1094731D03*
X1077832Y405347D03*
X1084591D03*
X1091351D03*
X1098111Y218147D03*
X1104871D03*
X1111631D03*
X1118391D03*
X1125150D03*
X1131910D03*
X1138670D03*
X1145430D03*
X1152190D03*
X1101491Y216196D03*
X1108251D03*
X1115011D03*
X1121771D03*
X1128530D03*
X1135290D03*
X1142050D03*
X1148810D03*
X1155570D03*
X1098111Y214247D03*
X1104871D03*
X1111631D03*
X1118391D03*
X1125150D03*
X1131910D03*
X1138670D03*
X1145430D03*
X1152190D03*
X1101491Y212296D03*
X1108251D03*
X1115011D03*
X1121771D03*
X1128530D03*
X1135290D03*
X1142050D03*
X1148810D03*
X1155570D03*
X1098111Y210346D03*
X1104871D03*
X1111631D03*
X1118391D03*
X1125150D03*
X1131910D03*
X1138670D03*
X1145430D03*
X1152190D03*
X1101491Y208397D03*
X1108251D03*
X1115011D03*
X1121771D03*
X1128530D03*
X1155570D03*
X1098111Y206447D03*
X1104871D03*
X1111631D03*
X1118391D03*
X1125150D03*
X1131910D03*
X1152190D03*
X1101491Y204496D03*
X1108251D03*
X1115011D03*
X1121771D03*
X1128530D03*
X1155570D03*
X1098111Y202547D03*
X1104871D03*
X1111631D03*
X1118391D03*
X1125150D03*
X1131910D03*
X1101491Y239596D03*
X1108251D03*
X1115011D03*
X1121771D03*
X1128530D03*
X1135290D03*
X1142050D03*
X1148810D03*
X1155570D03*
X1098111Y237647D03*
X1104871D03*
X1111631D03*
X1118391D03*
X1125150D03*
X1131910D03*
X1138670D03*
X1145430D03*
X1152190D03*
X1101491Y235696D03*
X1108251D03*
X1115011D03*
X1121771D03*
X1128530D03*
X1135290D03*
X1142050D03*
X1148810D03*
X1155570D03*
X1098111Y233746D03*
X1104871D03*
X1111631D03*
X1118391D03*
X1125150D03*
X1131910D03*
X1138670D03*
X1145430D03*
X1152190D03*
X1101491Y231797D03*
X1108251D03*
X1115011D03*
X1121771D03*
X1128530D03*
X1135290D03*
X1142050D03*
X1148810D03*
X1155570D03*
X1101491Y227896D03*
X1108251D03*
X1115011D03*
X1121771D03*
X1128530D03*
X1135290D03*
X1142050D03*
X1148810D03*
X1155570D03*
X1098111Y225947D03*
X1104871D03*
X1111631D03*
X1118391D03*
X1125150D03*
X1131910D03*
X1138670D03*
X1145430D03*
X1152190D03*
X1101491Y223996D03*
X1108251D03*
X1115011D03*
X1121771D03*
X1128530D03*
X1135290D03*
X1142050D03*
X1148810D03*
X1155570D03*
X1098111Y222047D03*
X1104871D03*
X1111631D03*
X1118391D03*
X1125150D03*
X1131910D03*
X1138670D03*
X1145430D03*
X1152190D03*
X1101491Y220096D03*
X1108251D03*
X1115011D03*
X1121771D03*
X1128530D03*
X1135290D03*
X1142050D03*
X1148810D03*
X1155570D03*
X1121771Y278596D03*
X1128530D03*
X1135290D03*
X1142050D03*
X1148810D03*
X1155570D03*
X1125150Y276646D03*
X1131910D03*
X1138670D03*
X1145430D03*
X1152190D03*
X1121771Y274696D03*
X1128530D03*
X1135290D03*
X1142050D03*
X1148810D03*
X1155570D03*
X1118391Y272747D03*
X1125150D03*
X1131910D03*
X1138670D03*
X1145430D03*
X1152190D03*
X1115011Y270796D03*
X1121771D03*
X1128530D03*
X1135290D03*
X1142050D03*
X1148810D03*
X1155570D03*
X1111631Y268847D03*
X1118391D03*
X1125150D03*
X1131910D03*
X1138670D03*
X1145430D03*
X1152190D03*
X1108251Y266896D03*
X1115011D03*
X1121771D03*
X1128530D03*
X1135290D03*
X1142050D03*
X1148810D03*
X1155570D03*
X1104871Y264947D03*
X1111631D03*
X1118391D03*
X1125150D03*
X1131910D03*
X1138670D03*
X1145430D03*
X1152190D03*
X1101491Y262996D03*
X1108251D03*
X1115011D03*
X1121771D03*
X1128530D03*
X1135290D03*
X1142050D03*
X1148810D03*
X1098111Y261047D03*
X1104871D03*
X1111631D03*
X1118391D03*
X1125150D03*
X1131910D03*
X1138670D03*
X1145430D03*
X1152190D03*
X1101491Y259096D03*
X1108251D03*
X1115011D03*
X1121771D03*
X1128530D03*
X1135290D03*
X1142050D03*
X1148810D03*
X1098111Y257147D03*
X1104871D03*
X1111631D03*
X1118391D03*
X1125150D03*
X1131910D03*
X1138670D03*
X1145430D03*
X1152190D03*
X1101491Y255196D03*
X1108251D03*
X1115011D03*
X1121771D03*
X1128530D03*
X1135290D03*
X1142050D03*
X1148810D03*
X1098111Y253247D03*
X1104871D03*
X1111631D03*
X1118391D03*
X1125150D03*
X1131910D03*
X1138670D03*
X1145430D03*
X1152190D03*
X1101491Y251296D03*
X1108251D03*
X1115011D03*
X1121771D03*
X1128530D03*
X1135290D03*
X1142050D03*
X1148810D03*
X1155570D03*
X1098111Y249347D03*
X1104871D03*
X1111631D03*
X1118391D03*
X1125150D03*
X1131910D03*
X1138670D03*
X1145430D03*
X1152190D03*
X1101491Y247396D03*
X1108251D03*
X1115011D03*
X1121771D03*
X1128530D03*
X1135290D03*
X1142050D03*
X1148810D03*
X1155570D03*
X1098111Y245447D03*
X1104871D03*
X1111631D03*
X1118391D03*
X1125150D03*
X1131910D03*
X1138670D03*
X1145430D03*
X1152190D03*
X1101491Y243496D03*
X1108251D03*
X1115011D03*
X1121771D03*
X1128530D03*
X1135290D03*
X1142050D03*
X1148810D03*
X1155570D03*
X1098111Y241547D03*
X1104871D03*
X1111631D03*
X1118391D03*
X1125150D03*
X1131910D03*
X1138670D03*
X1145430D03*
X1152190D03*
X1098111Y229847D03*
X1104871D03*
X1111631D03*
X1118391D03*
X1125150D03*
X1131910D03*
X1138670D03*
X1145430D03*
X1152190D03*
X1108251Y340996D03*
X1115011D03*
X1121771D03*
X1128530D03*
X1135290D03*
X1142050D03*
X1148810D03*
X1111631Y339047D03*
X1118391D03*
X1125150D03*
X1131910D03*
X1138670D03*
X1145430D03*
X1152190D03*
X1115011Y337096D03*
X1121771D03*
X1128530D03*
X1135290D03*
X1142050D03*
X1148810D03*
X1155570D03*
X1118391Y335147D03*
X1125150D03*
X1131910D03*
X1138670D03*
X1145430D03*
X1152190D03*
X1121771Y333196D03*
X1128530D03*
X1135290D03*
X1142050D03*
X1148810D03*
X1155570D03*
X1125150Y331247D03*
X1131910D03*
X1138670D03*
X1145430D03*
X1152190D03*
X1121771Y329296D03*
X1128530D03*
X1135290D03*
X1142050D03*
X1148810D03*
X1155570D03*
X1125150Y327347D03*
X1131910D03*
X1138670D03*
X1145430D03*
X1152190D03*
X1121771Y325396D03*
X1128530D03*
X1135290D03*
X1142050D03*
X1148810D03*
X1155570D03*
X1125150Y323446D03*
X1131910D03*
X1138670D03*
X1145430D03*
X1152190D03*
X1121771Y321496D03*
X1128530D03*
X1135290D03*
X1142050D03*
X1148810D03*
X1155570D03*
X1125150Y319547D03*
X1131910D03*
X1138670D03*
X1145430D03*
X1152190D03*
X1121771Y317596D03*
X1128530D03*
X1135290D03*
X1142050D03*
X1148810D03*
X1155570D03*
X1125150Y315647D03*
X1131910D03*
X1138670D03*
X1145430D03*
X1152190D03*
X1121771Y313696D03*
X1128530D03*
X1135290D03*
X1142050D03*
X1148810D03*
X1155570D03*
X1125150Y311747D03*
X1131910D03*
X1138670D03*
X1145430D03*
X1152190D03*
X1121771Y309797D03*
X1128530D03*
X1135290D03*
X1142050D03*
X1148810D03*
X1155570D03*
X1125150Y307847D03*
X1131910D03*
X1138670D03*
X1145430D03*
X1152190D03*
X1121771Y305896D03*
X1128530D03*
X1135290D03*
X1142050D03*
X1148810D03*
X1155570D03*
X1125150Y303947D03*
X1131910D03*
X1138670D03*
X1145430D03*
X1152190D03*
X1121771Y301996D03*
X1128530D03*
X1135290D03*
X1142050D03*
X1148810D03*
X1155570D03*
X1125150Y300047D03*
X1131910D03*
X1138670D03*
X1145430D03*
X1152190D03*
X1121771Y298096D03*
X1128530D03*
X1135290D03*
X1142050D03*
X1148810D03*
X1155570D03*
X1125150Y296147D03*
X1131910D03*
X1138670D03*
X1145430D03*
X1152190D03*
X1121771Y294196D03*
X1128530D03*
X1135290D03*
X1142050D03*
X1148810D03*
X1155570D03*
X1125150Y292247D03*
X1131910D03*
X1138670D03*
X1145430D03*
X1152190D03*
X1121771Y290296D03*
X1128530D03*
X1135290D03*
X1142050D03*
X1148810D03*
X1155570D03*
X1125150Y288347D03*
X1131910D03*
X1138670D03*
X1145430D03*
X1152190D03*
X1121771Y286396D03*
X1128530D03*
X1135290D03*
X1142050D03*
X1148810D03*
X1155570D03*
X1125150Y284447D03*
X1131910D03*
X1138670D03*
X1145430D03*
X1152190D03*
X1121771Y282496D03*
X1128530D03*
X1135290D03*
X1142050D03*
X1148810D03*
X1155570D03*
X1125150Y280547D03*
X1131910D03*
X1138670D03*
X1145430D03*
X1152190D03*
X1101491Y403396D03*
X1108251D03*
X1115011D03*
X1121771D03*
X1128530D03*
X1135290D03*
X1098111Y401447D03*
X1104871D03*
X1111631D03*
X1118391D03*
X1125150D03*
X1131910D03*
X1138670D03*
X1101491Y399496D03*
X1108251D03*
X1115011D03*
X1121771D03*
X1128530D03*
X1135290D03*
X1142050D03*
X1098111Y397546D03*
X1104871D03*
X1111631D03*
X1118391D03*
X1125150D03*
X1131910D03*
X1138670D03*
X1145430D03*
X1152190D03*
X1101491Y395597D03*
X1108251D03*
X1115011D03*
X1121771D03*
X1128530D03*
X1135290D03*
X1142050D03*
X1148810D03*
X1155570D03*
X1098111Y393647D03*
X1104871D03*
X1111631D03*
X1118391D03*
X1125150D03*
X1131910D03*
X1138670D03*
X1145430D03*
X1152190D03*
X1101491Y391696D03*
X1108251D03*
X1115011D03*
X1121771D03*
X1128530D03*
X1135290D03*
X1142050D03*
X1148810D03*
X1155570D03*
X1098111Y389747D03*
X1104871D03*
X1111631D03*
X1118391D03*
X1125150D03*
X1131910D03*
X1138670D03*
X1145430D03*
X1152190D03*
X1101491Y387796D03*
X1108251D03*
X1115011D03*
X1121771D03*
X1128530D03*
X1135290D03*
X1142050D03*
X1148810D03*
X1155570D03*
X1098111Y385847D03*
X1104871D03*
X1111631D03*
X1118391D03*
X1125150D03*
X1131910D03*
X1138670D03*
X1145430D03*
X1152190D03*
X1101491Y383896D03*
X1108251D03*
X1115011D03*
X1121771D03*
X1128530D03*
X1135290D03*
X1142050D03*
X1148810D03*
X1155570D03*
X1098111Y381947D03*
X1104871D03*
X1111631D03*
X1118391D03*
X1125150D03*
X1131910D03*
X1138670D03*
X1145430D03*
X1152190D03*
X1098111Y378047D03*
X1104871D03*
X1111631D03*
X1118391D03*
X1125150D03*
X1131910D03*
X1138670D03*
X1145430D03*
X1152190D03*
X1101491Y376096D03*
X1108251D03*
X1115011D03*
X1121771D03*
X1128530D03*
X1135290D03*
X1142050D03*
X1148810D03*
X1155570D03*
X1098111Y374146D03*
X1104871D03*
X1111631D03*
X1118391D03*
X1125150D03*
X1131910D03*
X1138670D03*
X1145430D03*
X1152190D03*
X1101491Y372197D03*
X1108251D03*
X1115011D03*
X1121771D03*
X1128530D03*
X1135290D03*
X1142050D03*
X1148810D03*
X1155570D03*
X1098111Y370247D03*
X1104871D03*
X1111631D03*
X1118391D03*
X1125150D03*
X1131910D03*
X1138670D03*
X1145430D03*
X1152190D03*
X1101491Y368296D03*
X1108251D03*
X1115011D03*
X1121771D03*
X1128530D03*
X1135290D03*
X1142050D03*
X1148810D03*
X1155570D03*
X1098111Y366347D03*
X1104871D03*
X1111631D03*
X1118391D03*
X1125150D03*
X1131910D03*
X1138670D03*
X1145430D03*
X1152190D03*
X1101491Y364396D03*
X1108251D03*
X1115011D03*
X1121771D03*
X1128530D03*
X1135290D03*
X1142050D03*
X1148810D03*
X1155570D03*
X1098111Y362447D03*
X1104871D03*
X1111631D03*
X1118391D03*
X1125150D03*
X1131910D03*
X1138670D03*
X1145430D03*
X1152190D03*
X1101491Y360496D03*
X1108251D03*
X1115011D03*
X1121771D03*
X1128530D03*
X1135290D03*
X1142050D03*
X1148810D03*
X1155570D03*
X1098111Y358547D03*
X1104871D03*
X1111631D03*
X1118391D03*
X1125150D03*
X1131910D03*
X1138670D03*
X1145430D03*
X1152190D03*
X1101491Y356596D03*
X1108251D03*
X1115011D03*
X1121771D03*
X1128530D03*
X1135290D03*
X1142050D03*
X1148810D03*
X1155570D03*
X1098111Y354647D03*
X1104871D03*
X1111631D03*
X1118391D03*
X1125150D03*
X1131910D03*
X1138670D03*
X1145430D03*
X1152190D03*
X1101491Y352696D03*
X1108251D03*
X1115011D03*
X1121771D03*
X1128530D03*
X1135290D03*
X1142050D03*
X1148810D03*
X1155570D03*
X1098111Y350747D03*
X1104871D03*
X1111631D03*
X1118391D03*
X1125150D03*
X1131910D03*
X1138670D03*
X1145430D03*
X1152190D03*
X1101491Y348796D03*
X1108251D03*
X1115011D03*
X1121771D03*
X1128530D03*
X1135290D03*
X1142050D03*
X1148810D03*
X1098111Y346847D03*
X1104871D03*
X1111631D03*
X1118391D03*
X1125150D03*
X1131910D03*
X1138670D03*
X1145430D03*
X1152190D03*
X1101491Y344896D03*
X1108251D03*
X1115011D03*
X1121771D03*
X1128530D03*
X1135290D03*
X1142050D03*
X1148810D03*
X1104871Y342947D03*
X1111631D03*
X1118391D03*
X1125150D03*
X1131910D03*
X1138670D03*
X1145430D03*
X1152190D03*
X1101491Y379996D03*
X1108251D03*
X1115011D03*
X1121771D03*
X1128530D03*
X1135290D03*
X1142050D03*
X1148810D03*
X1155570D03*
X1098111Y405347D03*
X1104871D03*
X1111631D03*
X1118391D03*
X1125150D03*
X1131910D03*
X1185989Y218147D03*
X1192749D03*
X1199509D03*
X1206269D03*
X1158950D03*
X1165710D03*
X1172469D03*
X1179229D03*
X1182609Y216196D03*
X1189369D03*
X1196129D03*
X1202889D03*
X1162330D03*
X1169089D03*
X1175849D03*
X1209649D03*
X1185989Y214247D03*
X1192749D03*
X1199509D03*
X1206269D03*
X1158950D03*
X1165710D03*
X1172469D03*
X1179229D03*
X1182609Y212296D03*
X1189369D03*
X1196129D03*
X1202889D03*
X1162330D03*
X1169089D03*
X1175849D03*
X1185989Y210346D03*
X1192749D03*
X1199509D03*
X1206269D03*
X1158950D03*
X1165710D03*
X1172469D03*
X1179229D03*
X1182609Y208397D03*
X1189369D03*
X1196129D03*
X1202889D03*
X1162330D03*
X1169089D03*
X1175849D03*
X1185989Y206447D03*
X1192749D03*
X1199509D03*
X1158950D03*
X1165710D03*
X1172469D03*
X1179229D03*
X1182609Y204496D03*
X1189369D03*
X1196129D03*
X1202889D03*
X1162330D03*
X1169089D03*
X1175849D03*
X1185989Y202547D03*
X1192749D03*
X1199509D03*
X1158950D03*
X1165710D03*
X1172469D03*
X1179229D03*
X1182609Y239596D03*
X1189369D03*
X1196129D03*
X1202889D03*
X1162330D03*
X1169089D03*
X1175849D03*
X1209649D03*
X1185989Y237647D03*
X1192749D03*
X1199509D03*
X1206269D03*
X1158950D03*
X1165710D03*
X1172469D03*
X1179229D03*
X1182609Y235696D03*
X1189369D03*
X1196129D03*
X1202889D03*
X1162330D03*
X1169089D03*
X1175849D03*
X1209649D03*
X1185989Y233746D03*
X1192749D03*
X1199509D03*
X1206269D03*
X1158950D03*
X1165710D03*
X1172469D03*
X1179229D03*
X1182609Y231797D03*
X1189369D03*
X1196129D03*
X1202889D03*
X1162330D03*
X1169089D03*
X1175849D03*
X1209649D03*
X1182609Y227896D03*
X1189369D03*
X1196129D03*
X1202889D03*
X1162330D03*
X1169089D03*
X1175849D03*
X1209649D03*
X1185989Y225947D03*
X1192749D03*
X1199509D03*
X1206269D03*
X1158950D03*
X1165710D03*
X1172469D03*
X1179229D03*
X1182609Y223996D03*
X1189369D03*
X1196129D03*
X1202889D03*
X1162330D03*
X1169089D03*
X1175849D03*
X1209649D03*
X1185989Y222047D03*
X1192749D03*
X1199509D03*
X1206269D03*
X1158950D03*
X1165710D03*
X1172469D03*
X1179229D03*
X1182609Y220096D03*
X1189369D03*
X1196129D03*
X1202889D03*
X1162330D03*
X1169089D03*
X1175849D03*
X1209649D03*
X1182609Y278596D03*
X1189369D03*
X1196129D03*
X1202889D03*
X1162330D03*
X1169089D03*
X1175849D03*
X1185989Y276646D03*
X1192749D03*
X1199509D03*
X1206269D03*
X1158950D03*
X1165710D03*
X1172469D03*
X1179229D03*
X1182609Y274696D03*
X1189369D03*
X1196129D03*
X1202889D03*
X1162330D03*
X1169089D03*
X1175849D03*
X1209649D03*
X1185989Y272747D03*
X1192749D03*
X1199509D03*
X1206269D03*
X1158950D03*
X1165710D03*
X1172469D03*
X1179229D03*
X1182609Y270796D03*
X1189369D03*
X1196129D03*
X1202889D03*
X1162330D03*
X1169089D03*
X1175849D03*
X1209649D03*
X1185989Y268847D03*
X1192749D03*
X1199509D03*
X1206269D03*
X1158950D03*
X1165710D03*
X1172469D03*
X1179229D03*
X1182609Y266896D03*
X1189369D03*
X1196129D03*
X1202889D03*
X1169089D03*
X1175849D03*
X1209649D03*
X1185989Y264947D03*
X1192749D03*
X1199509D03*
X1206269D03*
X1165710D03*
X1172469D03*
X1179229D03*
X1182609Y262996D03*
X1189369D03*
X1196129D03*
X1202889D03*
X1169089D03*
X1175849D03*
X1209649D03*
X1185989Y261047D03*
X1192749D03*
X1199509D03*
X1206269D03*
X1165710D03*
X1172469D03*
X1179229D03*
X1182609Y259096D03*
X1189369D03*
X1196129D03*
X1202889D03*
X1169089D03*
X1175849D03*
X1209649D03*
X1185989Y257147D03*
X1192749D03*
X1199509D03*
X1206269D03*
X1165710D03*
X1172469D03*
X1179229D03*
X1182609Y255196D03*
X1189369D03*
X1196129D03*
X1202889D03*
X1162330D03*
X1169089D03*
X1175849D03*
X1209649D03*
X1185989Y253247D03*
X1192749D03*
X1199509D03*
X1206269D03*
X1158950D03*
X1165710D03*
X1172469D03*
X1179229D03*
X1182609Y251296D03*
X1189369D03*
X1196129D03*
X1202889D03*
X1162330D03*
X1169089D03*
X1175849D03*
X1209649D03*
X1185989Y249347D03*
X1192749D03*
X1199509D03*
X1206269D03*
X1158950D03*
X1165710D03*
X1172469D03*
X1179229D03*
X1182609Y247396D03*
X1189369D03*
X1196129D03*
X1202889D03*
X1162330D03*
X1169089D03*
X1175849D03*
X1209649D03*
X1185989Y245447D03*
X1192749D03*
X1199509D03*
X1206269D03*
X1158950D03*
X1165710D03*
X1172469D03*
X1179229D03*
X1182609Y243496D03*
X1189369D03*
X1196129D03*
X1202889D03*
X1162330D03*
X1169089D03*
X1175849D03*
X1209649D03*
X1185989Y241547D03*
X1192749D03*
X1199509D03*
X1206269D03*
X1158950D03*
X1165710D03*
X1172469D03*
X1179229D03*
X1185989Y229847D03*
X1192749D03*
X1199509D03*
X1206269D03*
X1158950D03*
X1165710D03*
X1172469D03*
X1179229D03*
X1182609Y340996D03*
X1189369D03*
X1196129D03*
X1202889D03*
X1162330D03*
X1169089D03*
X1175849D03*
X1209649D03*
X1185989Y339047D03*
X1192749D03*
X1199509D03*
X1206269D03*
X1158950D03*
X1165710D03*
X1172469D03*
X1179229D03*
X1182609Y337096D03*
X1189369D03*
X1196129D03*
X1202889D03*
X1162330D03*
X1169089D03*
X1175849D03*
X1209649D03*
X1185989Y335147D03*
X1192749D03*
X1199509D03*
X1206269D03*
X1158950D03*
X1165710D03*
X1172469D03*
X1179229D03*
X1182609Y333196D03*
X1189369D03*
X1196129D03*
X1202889D03*
X1162330D03*
X1169089D03*
X1175849D03*
X1209649D03*
X1185989Y331247D03*
X1192749D03*
X1199509D03*
X1206269D03*
X1158950D03*
X1165710D03*
X1172469D03*
X1179229D03*
X1182609Y329296D03*
X1189369D03*
X1196129D03*
X1202889D03*
X1162330D03*
X1169089D03*
X1175849D03*
X1185989Y327347D03*
X1192749D03*
X1199509D03*
X1206269D03*
X1158950D03*
X1165710D03*
X1172469D03*
X1179229D03*
X1182609Y325396D03*
X1189369D03*
X1196129D03*
X1202889D03*
X1162330D03*
X1169089D03*
X1175849D03*
X1185989Y323446D03*
X1192749D03*
X1199509D03*
X1206269D03*
X1158950D03*
X1165710D03*
X1172469D03*
X1179229D03*
X1182609Y321496D03*
X1189369D03*
X1196129D03*
X1202889D03*
X1162330D03*
X1169089D03*
X1175849D03*
X1185989Y319547D03*
X1192749D03*
X1199509D03*
X1206269D03*
X1158950D03*
X1165710D03*
X1172469D03*
X1179229D03*
X1182609Y317596D03*
X1189369D03*
X1196129D03*
X1202889D03*
X1162330D03*
X1169089D03*
X1175849D03*
X1185989Y315647D03*
X1192749D03*
X1199509D03*
X1158950D03*
X1165710D03*
X1172469D03*
X1179229D03*
X1182609Y313696D03*
X1189369D03*
X1196129D03*
X1202889D03*
X1162330D03*
X1169089D03*
X1175849D03*
X1185989Y311747D03*
X1192749D03*
X1199509D03*
X1158950D03*
X1165710D03*
X1172469D03*
X1179229D03*
X1182609Y309797D03*
X1189369D03*
X1196129D03*
X1202889D03*
X1162330D03*
X1169089D03*
X1175849D03*
X1185989Y307847D03*
X1192749D03*
X1199509D03*
X1158950D03*
X1165710D03*
X1172469D03*
X1179229D03*
X1182609Y305896D03*
X1189369D03*
X1196129D03*
X1202889D03*
X1162330D03*
X1169089D03*
X1175849D03*
X1185989Y303947D03*
X1192749D03*
X1199509D03*
X1158950D03*
X1165710D03*
X1172469D03*
X1179229D03*
X1182609Y301996D03*
X1189369D03*
X1196129D03*
X1202889D03*
X1162330D03*
X1169089D03*
X1175849D03*
X1185989Y300047D03*
X1192749D03*
X1199509D03*
X1158950D03*
X1165710D03*
X1172469D03*
X1179229D03*
X1182609Y298096D03*
X1189369D03*
X1196129D03*
X1202889D03*
X1162330D03*
X1169089D03*
X1175849D03*
X1185989Y296147D03*
X1192749D03*
X1199509D03*
X1158950D03*
X1165710D03*
X1172469D03*
X1179229D03*
X1182609Y294196D03*
X1189369D03*
X1196129D03*
X1202889D03*
X1162330D03*
X1169089D03*
X1175849D03*
X1185989Y292247D03*
X1192749D03*
X1199509D03*
X1158950D03*
X1165710D03*
X1172469D03*
X1179229D03*
X1182609Y290296D03*
X1189369D03*
X1196129D03*
X1202889D03*
X1162330D03*
X1169089D03*
X1175849D03*
X1185989Y288347D03*
X1192749D03*
X1199509D03*
X1158950D03*
X1165710D03*
X1172469D03*
X1179229D03*
X1182609Y286396D03*
X1189369D03*
X1196129D03*
X1202889D03*
X1162330D03*
X1169089D03*
X1175849D03*
X1185989Y284447D03*
X1192749D03*
X1199509D03*
X1206269D03*
X1158950D03*
X1165710D03*
X1172469D03*
X1179229D03*
X1182609Y282496D03*
X1189369D03*
X1196129D03*
X1202889D03*
X1162330D03*
X1169089D03*
X1175849D03*
X1185989Y280547D03*
X1192749D03*
X1199509D03*
X1206269D03*
X1158950D03*
X1165710D03*
X1172469D03*
X1179229D03*
X1182609Y403396D03*
X1189369D03*
X1196129D03*
X1162330D03*
X1169089D03*
X1175849D03*
X1185989Y401447D03*
X1192749D03*
X1199509D03*
X1158950D03*
X1165710D03*
X1172469D03*
X1179229D03*
X1182609Y399496D03*
X1189369D03*
X1196129D03*
X1202889D03*
X1162330D03*
X1169089D03*
X1175849D03*
X1185989Y397546D03*
X1192749D03*
X1199509D03*
X1158950D03*
X1165710D03*
X1172469D03*
X1179229D03*
X1182609Y395597D03*
X1189369D03*
X1196129D03*
X1202889D03*
X1162330D03*
X1169089D03*
X1175849D03*
X1185989Y393647D03*
X1192749D03*
X1199509D03*
X1206269D03*
X1158950D03*
X1165710D03*
X1172469D03*
X1179229D03*
X1182609Y391696D03*
X1189369D03*
X1196129D03*
X1202889D03*
X1162330D03*
X1169089D03*
X1175849D03*
X1185989Y389747D03*
X1192749D03*
X1199509D03*
X1206269D03*
X1158950D03*
X1165710D03*
X1172469D03*
X1179229D03*
X1182609Y387796D03*
X1189369D03*
X1196129D03*
X1202889D03*
X1162330D03*
X1169089D03*
X1175849D03*
X1185989Y385847D03*
X1192749D03*
X1199509D03*
X1206269D03*
X1158950D03*
X1165710D03*
X1172469D03*
X1179229D03*
X1182609Y383896D03*
X1189369D03*
X1196129D03*
X1202889D03*
X1162330D03*
X1169089D03*
X1175849D03*
X1185989Y381947D03*
X1192749D03*
X1199509D03*
X1206269D03*
X1158950D03*
X1165710D03*
X1172469D03*
X1179229D03*
X1185989Y378047D03*
X1192749D03*
X1199509D03*
X1206269D03*
X1158950D03*
X1165710D03*
X1172469D03*
X1179229D03*
X1182609Y376096D03*
X1189369D03*
X1196129D03*
X1202889D03*
X1162330D03*
X1169089D03*
X1175849D03*
X1185989Y374146D03*
X1192749D03*
X1199509D03*
X1206269D03*
X1158950D03*
X1165710D03*
X1172469D03*
X1179229D03*
X1182609Y372197D03*
X1189369D03*
X1196129D03*
X1202889D03*
X1162330D03*
X1169089D03*
X1175849D03*
X1185989Y370247D03*
X1192749D03*
X1199509D03*
X1206269D03*
X1158950D03*
X1165710D03*
X1172469D03*
X1179229D03*
X1182609Y368296D03*
X1189369D03*
X1196129D03*
X1202889D03*
X1162330D03*
X1169089D03*
X1175849D03*
X1185989Y366347D03*
X1192749D03*
X1199509D03*
X1206269D03*
X1158950D03*
X1165710D03*
X1172469D03*
X1179229D03*
X1182609Y364396D03*
X1189369D03*
X1196129D03*
X1202889D03*
X1162330D03*
X1169089D03*
X1175849D03*
X1185989Y362447D03*
X1192749D03*
X1199509D03*
X1206269D03*
X1158950D03*
X1165710D03*
X1172469D03*
X1179229D03*
X1182609Y360496D03*
X1189369D03*
X1196129D03*
X1202889D03*
X1162330D03*
X1169089D03*
X1175849D03*
X1209649D03*
X1185989Y358547D03*
X1192749D03*
X1199509D03*
X1206269D03*
X1158950D03*
X1165710D03*
X1172469D03*
X1179229D03*
X1182609Y356596D03*
X1189369D03*
X1196129D03*
X1202889D03*
X1162330D03*
X1169089D03*
X1175849D03*
X1209649D03*
X1185989Y354647D03*
X1192749D03*
X1199509D03*
X1206269D03*
X1158950D03*
X1165710D03*
X1172469D03*
X1179229D03*
X1182609Y352696D03*
X1189369D03*
X1196129D03*
X1202889D03*
X1169089D03*
X1175849D03*
X1209649D03*
X1185989Y350747D03*
X1192749D03*
X1199509D03*
X1206269D03*
X1165710D03*
X1172469D03*
X1179229D03*
X1182609Y348796D03*
X1189369D03*
X1196129D03*
X1202889D03*
X1169089D03*
X1175849D03*
X1209649D03*
X1185989Y346847D03*
X1192749D03*
X1199509D03*
X1206269D03*
X1165710D03*
X1172469D03*
X1179229D03*
X1182609Y344896D03*
X1189369D03*
X1196129D03*
X1202889D03*
X1169089D03*
X1175849D03*
X1209649D03*
X1185989Y342947D03*
X1192749D03*
X1199509D03*
X1206269D03*
X1165710D03*
X1172469D03*
X1179229D03*
X1182609Y379996D03*
X1189369D03*
X1196129D03*
X1202889D03*
X1162330D03*
X1169089D03*
X1175849D03*
X1185989Y405347D03*
X1192749D03*
X1158950D03*
X1165710D03*
X1172469D03*
X1179229D03*
G54D202*
X1466733Y585953D03*
X1502030Y591554D03*
G54D221*
X1487858Y608784D03*
X1523396Y610052D03*
G54D230*
X1560365Y243947D03*
X1585165D03*
G54D320*
X1969883Y207007D03*
Y242441D03*
G54D113*
X348000Y13200D03*
X353500D03*
X343142D03*
X337642D03*
X330142D03*
X324642D03*
X317942D03*
X312442D03*
X348000Y51000D03*
X353500D03*
X343142D03*
X337642D03*
X330142D03*
X324642D03*
X317942D03*
X312442D03*
X307693Y495595D03*
X313193D03*
X348000Y552000D03*
X353500D03*
X343142D03*
X337642D03*
X330142D03*
X324642D03*
X317872D03*
X312372D03*
X348000Y589800D03*
X353500D03*
X343142D03*
X337642D03*
X330142D03*
X324642D03*
X317942D03*
X312442D03*
X360792Y13078D03*
X366292D03*
X411650Y13200D03*
X417150D03*
X399200D03*
X404700D03*
X361178Y50492D03*
X366678D03*
X411650Y51000D03*
X417150D03*
X399200D03*
X404700D03*
X360292Y589800D03*
X365792D03*
X411650Y552000D03*
X417150D03*
X399200D03*
X404700D03*
X366692D03*
X361192D03*
X411650Y589800D03*
X417150D03*
X399200D03*
X404700D03*
X437008Y13200D03*
X442508D03*
X424650D03*
X430150D03*
X437008Y51000D03*
X442508D03*
X424650D03*
X430150D03*
X437008Y552000D03*
X442508D03*
X424650D03*
X430150D03*
X437008Y589800D03*
X442508D03*
X424650D03*
X430150D03*
X967550Y13200D03*
X962050D03*
X967550Y51000D03*
X962050D03*
X957301Y495595D03*
X962801D03*
X967450Y552000D03*
X961950D03*
X967450Y589800D03*
X961950D03*
X1010400Y13078D03*
X1015900D03*
X997608Y13200D03*
X1003108D03*
X992750D03*
X987250D03*
X979750D03*
X974250D03*
X1010900Y50800D03*
X1016400D03*
X997608Y51000D03*
X1003108D03*
X992750D03*
X987250D03*
X979750D03*
X974250D03*
X1009700Y589500D03*
X1015200D03*
X1016000Y551700D03*
X1010500D03*
X997608Y552000D03*
X1003108D03*
X992750D03*
X987250D03*
X979850D03*
X974350D03*
X997608Y589800D03*
X1003108D03*
X992750D03*
X987250D03*
X979750D03*
X974250D03*
X1086616Y13200D03*
X1092116D03*
X1074258D03*
X1079758D03*
X1061258D03*
X1066758D03*
X1048808D03*
X1054308D03*
X1086616Y51000D03*
X1092116D03*
X1074258D03*
X1079758D03*
X1061258D03*
X1066758D03*
X1048808D03*
X1054308D03*
X1086616Y552000D03*
X1092116D03*
X1074258D03*
X1079758D03*
X1061258D03*
X1066758D03*
X1048808D03*
X1054308D03*
X1086616Y589800D03*
X1092116D03*
X1074258D03*
X1079758D03*
X1061258D03*
X1066758D03*
X1048808D03*
X1054308D03*
G54D212*
X1520972Y300937D03*
Y293257D03*
Y308617D03*
Y295817D03*
Y298377D03*
Y303497D03*
Y306057D03*
X1544472Y308617D03*
Y300937D03*
Y293257D03*
Y295817D03*
Y298377D03*
Y303497D03*
Y306057D03*
X1773471Y564015D03*
X1749971Y556335D03*
Y564015D03*
Y571695D03*
X1773471D03*
Y556335D03*
Y569135D03*
Y566575D03*
Y561455D03*
Y558895D03*
X1749971Y569135D03*
Y566575D03*
Y561455D03*
Y558895D03*
X1748800Y581750D03*
X1772300D03*
Y586870D03*
Y584310D03*
X1748800Y586870D03*
Y584310D03*
X1772300Y589430D03*
X1748800D03*
Y597110D03*
X1772300D03*
Y594550D03*
Y591990D03*
X1748800Y594550D03*
Y591990D03*
G54D131*
X634930Y487050D03*
X616930D03*
X634930Y481930D03*
X616930D03*
X634930Y484490D03*
X616930D03*
X634930Y479370D03*
X616930D03*
G54D20*
X-17200Y516800D03*
Y513300D03*
X-16500Y493000D03*
Y489500D03*
X34719Y16717D03*
Y13217D03*
X43819Y13901D03*
Y17401D03*
X46845Y17442D03*
Y13942D03*
X-1347Y23809D03*
Y27309D03*
X40796Y17406D03*
Y13906D03*
X37739Y16712D03*
Y13212D03*
X34597Y24567D03*
Y28067D03*
X28871Y-20458D03*
Y-16958D03*
X-1080Y60600D03*
Y57100D03*
X34500Y51000D03*
Y54500D03*
X4522Y57858D03*
Y54358D03*
X8000Y275500D03*
Y272000D03*
X11000Y275500D03*
Y272000D03*
X41000Y271450D03*
Y267950D03*
X37000Y271450D03*
Y267950D03*
X8000Y299000D03*
Y295500D03*
X5000Y299000D03*
Y295500D03*
X-1278Y464071D03*
Y460571D03*
X-5590Y521840D03*
Y518340D03*
X-2390D03*
Y521840D03*
X-13500Y493000D03*
Y489500D03*
X-8990Y523040D03*
Y519540D03*
X-12690Y519590D03*
Y523090D03*
X23800Y516500D03*
Y513000D03*
X27300Y516500D03*
Y513000D03*
X16990Y525130D03*
Y521630D03*
X25388Y504477D03*
Y507977D03*
X20490Y525130D03*
Y521630D03*
X710Y521890D03*
Y518390D03*
X-9900Y489500D03*
Y493000D03*
X52906Y13926D03*
Y17426D03*
X55942Y17445D03*
Y13945D03*
X49880Y17415D03*
Y13915D03*
X106000Y11328D03*
Y14828D03*
X56540Y-20308D03*
Y-16808D03*
X53340Y-20296D03*
Y-16796D03*
X105898Y49250D03*
Y52750D03*
X108077Y86864D03*
Y90364D03*
X104289Y128454D03*
Y124954D03*
X103250Y265180D03*
Y261680D03*
X87500Y275500D03*
Y279000D03*
X80500Y275500D03*
Y279000D03*
X84000Y275500D03*
Y279000D03*
X77000Y275500D03*
Y279000D03*
X73500Y275500D03*
Y279000D03*
X86078Y266950D03*
Y270450D03*
X103500Y322500D03*
Y319000D03*
X100000Y322500D03*
Y319000D03*
X75600Y328600D03*
Y332100D03*
X57000Y341500D03*
X60000D03*
X66000D03*
X72000Y341800D03*
X69000D03*
X63000Y341500D03*
X92370Y327770D03*
Y331270D03*
X89220Y331230D03*
Y327730D03*
X91710Y339200D03*
X87500Y318500D03*
Y322000D03*
X91500Y317800D03*
Y321300D03*
X70800Y317050D03*
Y313550D03*
X55500Y316250D03*
Y312750D03*
X56000Y307500D03*
Y304000D03*
X66500Y313250D03*
Y316750D03*
X61000Y313250D03*
Y316750D03*
X80500Y322020D03*
Y318520D03*
X78000Y341050D03*
X75000Y341500D03*
X50900Y295300D03*
Y298800D03*
X56000Y300000D03*
Y296500D03*
X84000Y318520D03*
Y322020D03*
X74500Y317000D03*
Y313500D03*
X96000Y287700D03*
Y291200D03*
X94630Y363220D03*
Y359720D03*
X57000Y345000D03*
X60000D03*
X66000D03*
X72000Y345300D03*
X69000D03*
X63000Y345000D03*
X91710Y342700D03*
X94519Y349333D03*
Y345833D03*
X94630Y356850D03*
Y353350D03*
X94710Y370914D03*
Y367414D03*
X78000Y344550D03*
X75000Y345000D03*
X88300Y383110D03*
Y386610D03*
X93296Y387604D03*
Y384104D03*
X72000Y391500D03*
Y395000D03*
X52500Y398000D03*
Y401500D03*
X56000Y398000D03*
Y401500D03*
X59500Y398000D03*
Y401500D03*
X49000Y398100D03*
Y401600D03*
X95396Y373774D03*
Y377274D03*
X57500Y385500D03*
Y382000D03*
X77300Y386614D03*
Y383114D03*
X80800Y386614D03*
Y383114D03*
X54000Y385500D03*
Y382000D03*
X91996Y377274D03*
Y373774D03*
X70525Y465138D03*
Y468638D03*
X109500Y11328D03*
Y14828D03*
X116500D03*
Y11328D03*
X113000D03*
Y14828D03*
X109392Y49250D03*
Y52750D03*
X112500Y49150D03*
Y52650D03*
X116000D03*
Y49150D03*
X117354Y90529D03*
Y87029D03*
X114284D03*
Y90529D03*
X111189Y86821D03*
Y90321D03*
X153200Y195600D03*
Y199100D03*
X117475Y168300D03*
Y164800D03*
X119400Y271600D03*
Y275100D03*
X118164Y304915D03*
Y308415D03*
X117976Y368958D03*
Y372458D03*
X156392Y407500D03*
Y404000D03*
X442700Y271500D03*
Y275000D03*
X428000Y271500D03*
Y275000D03*
X436000Y271500D03*
Y275000D03*
X432000Y271500D03*
Y275000D03*
X439500Y271500D03*
Y275000D03*
X436100Y326800D03*
Y330300D03*
X433100Y326800D03*
Y330300D03*
X439100Y326800D03*
Y330300D03*
X442100Y326800D03*
Y330300D03*
X658700Y29100D03*
Y25600D03*
X611000Y116700D03*
Y120200D03*
Y113700D03*
Y110200D03*
X639320Y274550D03*
Y271050D03*
X636708Y277735D03*
X641228Y247796D03*
Y251296D03*
X646000Y259100D03*
Y255600D03*
X655000Y278100D03*
X658500D03*
X651500D03*
X649500Y255600D03*
Y259100D03*
X636400Y259000D03*
Y255500D03*
X636708Y281235D03*
X649000Y342000D03*
X654000D03*
X659000D03*
X655500Y293500D03*
Y290000D03*
X655000Y281600D03*
X658638Y291123D03*
Y287623D03*
X658500Y281600D03*
X661730Y290008D03*
Y293508D03*
X651000Y291000D03*
Y294500D03*
X651500Y281600D03*
X647500Y291000D03*
Y294500D03*
X649000Y345500D03*
X654000D03*
X659000D03*
X640500Y406500D03*
Y410000D03*
X637000Y406500D03*
Y410000D03*
X710150Y-5950D03*
Y-9450D03*
X712000Y29000D03*
Y32500D03*
X712500Y17500D03*
Y21000D03*
X708900D03*
Y17500D03*
X708500Y32500D03*
Y29000D03*
X672900Y30600D03*
X686000Y30750D03*
X689500D03*
X686700Y27950D03*
Y24450D03*
X700500Y29000D03*
Y32500D03*
X664300Y28050D03*
Y31550D03*
X713937Y-9548D03*
Y-6048D03*
X722000Y20250D03*
Y16750D03*
X715937Y20952D03*
Y17452D03*
X704500Y28700D03*
Y32200D03*
X667800Y31550D03*
Y28050D03*
X682500Y30750D03*
X672900Y34100D03*
X686000Y34250D03*
X689500D03*
X716500Y53250D03*
Y49750D03*
X682500Y34250D03*
X723500Y247500D03*
Y244000D03*
X718000Y224600D03*
Y221100D03*
X720500Y247500D03*
Y244000D03*
X723500Y252500D03*
Y256000D03*
X714000D03*
Y252500D03*
X711000Y256000D03*
Y252500D03*
X717000D03*
Y256000D03*
X720500D03*
Y252500D03*
X707500Y256000D03*
Y252500D03*
X676000Y278100D03*
X672500D03*
X673500Y295000D03*
Y291500D03*
X692470Y293640D03*
Y290140D03*
X684000Y342000D03*
X674000D03*
X701000Y335500D03*
Y332000D03*
X705000Y335500D03*
Y332000D03*
X679000Y342000D03*
X669000D03*
X717900Y309200D03*
Y312700D03*
X701000Y303500D03*
Y307000D03*
Y322500D03*
Y319000D03*
X664000Y342000D03*
X725400Y300450D03*
Y296950D03*
X676000Y281600D03*
X672500D03*
X684000Y345500D03*
X674000D03*
X679400Y371200D03*
Y367700D03*
X689900Y371200D03*
Y367700D03*
X679000Y345500D03*
X669000D03*
X664000D03*
X693200Y416775D03*
Y420275D03*
X696400Y416775D03*
Y420275D03*
X683400Y414700D03*
Y411200D03*
X712100Y515250D03*
Y518750D03*
X708500D03*
Y515250D03*
X700500D03*
Y518750D03*
X669400Y515700D03*
Y519200D03*
X686000Y514250D03*
Y517750D03*
X689500Y520750D03*
Y517250D03*
X683550Y511200D03*
Y507700D03*
X672400Y519250D03*
Y515750D03*
X704500Y515250D03*
Y518750D03*
X675500Y519250D03*
Y515750D03*
X679000Y514250D03*
Y517750D03*
X682500Y514250D03*
Y517750D03*
X716400Y538800D03*
Y535300D03*
X714600Y574500D03*
Y578000D03*
X711000Y574500D03*
Y578000D03*
X759000Y11250D03*
Y14750D03*
X766000D03*
Y11250D03*
X762500D03*
Y14750D03*
X726500Y20250D03*
Y16750D03*
X755500Y11250D03*
Y14750D03*
X759000Y49250D03*
Y52750D03*
X766000D03*
Y49250D03*
X762500D03*
Y52750D03*
X759000Y88611D03*
Y92111D03*
X762500Y88611D03*
Y92111D03*
X766000D03*
Y88611D03*
X755500Y49250D03*
Y52750D03*
Y88611D03*
Y92111D03*
X762300Y213100D03*
Y216600D03*
X766947Y207070D03*
Y210570D03*
X728291Y247500D03*
Y244000D03*
X761600Y245520D03*
Y249020D03*
X726500Y252500D03*
Y256000D03*
X740697Y260490D03*
Y256990D03*
X761850Y275560D03*
Y279060D03*
X742400Y277850D03*
X748700Y276350D03*
Y272850D03*
X747886Y263659D03*
Y260159D03*
X742128Y270902D03*
Y267402D03*
X765134Y271186D03*
Y274686D03*
X764341Y239542D03*
Y243042D03*
X746870Y286050D03*
Y289550D03*
X742400Y281350D03*
X734200Y297650D03*
Y301150D03*
X728900Y300450D03*
Y296950D03*
X743070Y289500D03*
Y286000D03*
X765582Y303588D03*
Y307088D03*
X768367Y337062D03*
Y340562D03*
X762350Y343730D03*
Y347230D03*
X768059Y369287D03*
Y372787D03*
X730100Y573950D03*
Y577450D03*
X726500Y574000D03*
Y577500D03*
X730100Y600500D03*
Y604000D03*
X726800D03*
Y600500D03*
X804200Y195600D03*
Y199100D03*
X809000Y407500D03*
Y404000D03*
X1080500Y272000D03*
Y275500D03*
X1088000Y272000D03*
Y275500D03*
X1077000Y272000D03*
Y275500D03*
X1091500Y272000D03*
Y275500D03*
X1094764Y271972D03*
Y275472D03*
X1084500Y272000D03*
Y275500D03*
X1084580Y326760D03*
Y330260D03*
X1087680Y326760D03*
Y330260D03*
X1095000Y326600D03*
Y330100D03*
X1091180Y326660D03*
Y330160D03*
X1076270Y335780D03*
Y332280D03*
X1255400Y116917D03*
Y120417D03*
Y113917D03*
Y110417D03*
X1228906Y140251D03*
Y136751D03*
X1225775Y140219D03*
Y136719D03*
X1279550Y111670D03*
Y115170D03*
Y119170D03*
Y122670D03*
X1276704Y507538D03*
Y504038D03*
X1275540Y513490D03*
Y516990D03*
X1273687Y507491D03*
Y503991D03*
X1268805Y508940D03*
Y505440D03*
X1272060Y513590D03*
Y517090D03*
X1339500Y90000D03*
Y93500D03*
X1322000Y88000D03*
Y91500D03*
X1326600Y80900D03*
Y77400D03*
X1325500Y91500D03*
Y88000D03*
X1341600Y501750D03*
Y505250D03*
X1323900Y504750D03*
Y508250D03*
X1326900D03*
Y504750D03*
X1338300Y501750D03*
Y505250D03*
X1335100Y501700D03*
Y505200D03*
X1330000Y508250D03*
Y504750D03*
X1387497Y-3011D03*
Y489D03*
X1384371Y-3020D03*
Y480D03*
X1378170Y8888D03*
Y12388D03*
X1379556Y19907D03*
Y16407D03*
X1384200Y31700D03*
X1371591Y88967D03*
Y92467D03*
X1368591Y92450D03*
Y88950D03*
X1360700D03*
Y92450D03*
X1350500Y92640D03*
Y89140D03*
X1351500Y77000D03*
Y80500D03*
X1347500D03*
Y77000D03*
X1356010Y45574D03*
Y42074D03*
X1343500Y90000D03*
Y93500D03*
X1347000Y90000D03*
Y93500D03*
X1374500Y73500D03*
Y70000D03*
X1378000Y73500D03*
Y70000D03*
X1370100Y79500D03*
Y76000D03*
X1364700Y88950D03*
Y92450D03*
X1366100Y79500D03*
Y76000D03*
X1344000Y80500D03*
Y77000D03*
X1374177Y61982D03*
Y65482D03*
X1384200Y35200D03*
X1376550Y113600D03*
Y110100D03*
X1344900Y505250D03*
Y501750D03*
X1396871Y505800D03*
Y509300D03*
X1392953Y509379D03*
Y505879D03*
X1371500Y526000D03*
X1401960Y524955D03*
X1391291Y531936D03*
Y528436D03*
X1400222Y554185D03*
Y550685D03*
X1352000Y560600D03*
Y564100D03*
X1371500Y529500D03*
X1401960Y528455D03*
X1398620Y530921D03*
Y534421D03*
X1398226Y543462D03*
Y539962D03*
X1395120Y530921D03*
Y534421D03*
X1385800Y612500D03*
Y609000D03*
X1352332Y620000D03*
Y616500D03*
X1383879Y619250D03*
Y615750D03*
X1420337Y42977D03*
Y39477D03*
X1416837Y42977D03*
Y39477D03*
X1458136D03*
Y42977D03*
X1454636Y39477D03*
Y42977D03*
X1464086Y39477D03*
Y42977D03*
X1438936Y39477D03*
Y42977D03*
X1426286Y39477D03*
Y42977D03*
X1435436Y39477D03*
Y42977D03*
X1429786Y39477D03*
Y42977D03*
X1445186Y39477D03*
Y42977D03*
X1448686Y39477D03*
Y42977D03*
X1430117Y287489D03*
Y283989D03*
X1461700Y395500D03*
Y399000D03*
X1458450Y365450D03*
Y361950D03*
X1460500Y386000D03*
Y382500D03*
Y392500D03*
Y389000D03*
X1453000Y377750D03*
Y381250D03*
X1453900Y398100D03*
Y394600D03*
X1441800Y366400D03*
Y362900D03*
X1451560Y418179D03*
Y421679D03*
Y428279D03*
Y424779D03*
X1425560Y523955D03*
X1428800Y524000D03*
X1432200Y524050D03*
X1422000Y524000D03*
X1405460Y524955D03*
X1455000Y540750D03*
Y537250D03*
X1458000Y540750D03*
Y537250D03*
X1425560Y527455D03*
X1428800Y527500D03*
X1432200Y527550D03*
X1448900Y540600D03*
Y537100D03*
X1452000D03*
Y540600D03*
X1439200Y534600D03*
Y531100D03*
X1436160Y554655D03*
Y558155D03*
X1422000Y527500D03*
X1432560Y558155D03*
Y554655D03*
X1405460Y528455D03*
X1527600Y-2500D03*
Y1000D03*
X1516900Y-2500D03*
Y1000D03*
X1520100Y-2500D03*
Y1000D03*
X1513700Y-2500D03*
Y1000D03*
X1486486Y39477D03*
Y42977D03*
X1491836Y39577D03*
Y43077D03*
X1495336Y39577D03*
Y43077D03*
X1477036Y39477D03*
Y42977D03*
X1473536Y39477D03*
Y42977D03*
X1467586Y39477D03*
Y42977D03*
X1482986Y39477D03*
Y42977D03*
X1498985Y143065D03*
Y146565D03*
X1493750Y140400D03*
Y143900D03*
X1519200Y206700D03*
Y203200D03*
X1518000Y218250D03*
X1511000D03*
X1518000Y221750D03*
X1511000D03*
X1504453Y302789D03*
Y299289D03*
X1507476Y302789D03*
Y299289D03*
X1510476Y302816D03*
Y299316D03*
X1513476D03*
Y302816D03*
X1516910Y323940D03*
Y327440D03*
X1523000Y347250D03*
Y343750D03*
X1526000D03*
Y347250D03*
X1517000D03*
Y343750D03*
X1520000Y347250D03*
Y343750D03*
X1487000Y347250D03*
Y343750D03*
X1496000D03*
Y347250D03*
X1499000Y343750D03*
Y347250D03*
X1493000Y343750D03*
Y347250D03*
X1490000D03*
Y343750D03*
X1483000Y347250D03*
Y343750D03*
X1472500D03*
Y347250D03*
X1477000Y343750D03*
Y347250D03*
X1480000Y343750D03*
Y347250D03*
X1508000D03*
Y343750D03*
X1514000Y347250D03*
Y343750D03*
X1511000Y347250D03*
Y343750D03*
X1505000Y347250D03*
Y343750D03*
X1502000D03*
Y347250D03*
X1472500Y354250D03*
Y350750D03*
X1494950Y353000D03*
Y356500D03*
X1516960Y352580D03*
Y356080D03*
X1502030Y585894D03*
Y582394D03*
X1466647Y580512D03*
Y577012D03*
X1502268Y604439D03*
Y607939D03*
X1466800Y615439D03*
Y611939D03*
X1466500Y604750D03*
Y608250D03*
X1494300Y618900D03*
Y622400D03*
X1502268Y615439D03*
Y611939D03*
X1498182Y603774D03*
Y607274D03*
X1494982Y603849D03*
Y607349D03*
X1554800Y-2600D03*
Y900D03*
X1564400Y-2600D03*
Y900D03*
X1558000Y-2600D03*
Y900D03*
X1561200Y-2600D03*
Y900D03*
X1540000Y-2500D03*
Y1000D03*
X1534000Y-2500D03*
Y1000D03*
X1543500Y-2500D03*
Y1000D03*
X1530800Y-2500D03*
Y1000D03*
X1548400Y-2600D03*
Y900D03*
X1551600Y-2600D03*
Y900D03*
X1586500Y87000D03*
Y90500D03*
X1585500Y94500D03*
X1589500Y90500D03*
Y87000D03*
X1582500Y94500D03*
X1579998Y39484D03*
Y42984D03*
X1576498Y39484D03*
Y42984D03*
X1585948Y39484D03*
Y42984D03*
X1589448Y39484D03*
Y42984D03*
X1557398Y39684D03*
Y43184D03*
X1548248Y39484D03*
Y42984D03*
X1560898Y39684D03*
Y43184D03*
X1567048Y39484D03*
Y42984D03*
X1570548Y39484D03*
Y42984D03*
X1551748Y39484D03*
Y42984D03*
X1584183Y112179D03*
Y115679D03*
X1580920Y115685D03*
Y112185D03*
X1587222Y115669D03*
Y112169D03*
X1585500Y98000D03*
X1582500D03*
X1576731Y128410D03*
Y131910D03*
X1579000Y185250D03*
Y188750D03*
Y182250D03*
Y178750D03*
X1553000Y162900D03*
Y159400D03*
X1579000Y196750D03*
Y193250D03*
X1541000Y279750D03*
X1548000D03*
X1534000D03*
X1537500D03*
X1540000Y250750D03*
Y254250D03*
X1537000D03*
Y250750D03*
X1550852Y246702D03*
Y243202D03*
X1533000Y257600D03*
Y261100D03*
X1533900Y250750D03*
Y254250D03*
X1543399Y251250D03*
Y254750D03*
X1544500Y279750D03*
X1554400Y258800D03*
Y262300D03*
Y258800D03*
Y255300D03*
X1577500Y334250D03*
Y330750D03*
Y327750D03*
Y324250D03*
X1540957Y337323D03*
Y340823D03*
X1547651Y336246D03*
Y339746D03*
X1560500Y338500D03*
Y335000D03*
X1553500Y338250D03*
Y334750D03*
X1556500Y338250D03*
Y334750D03*
X1543957Y337323D03*
Y340823D03*
X1541000Y283250D03*
X1548000D03*
X1567500Y309750D03*
Y306250D03*
X1534000Y283250D03*
X1537500D03*
X1535250Y317800D03*
Y314300D03*
X1577500Y296000D03*
Y299500D03*
X1544500Y283250D03*
X1545500Y343750D03*
Y347250D03*
X1556500Y343750D03*
Y347250D03*
X1553500Y343750D03*
Y347250D03*
X1560500Y343750D03*
Y347250D03*
X1550500D03*
Y343750D03*
X1529000Y347250D03*
Y343750D03*
X1535000Y347250D03*
Y343750D03*
X1542500D03*
Y347250D03*
X1538000D03*
Y343750D03*
X1532000D03*
Y347250D03*
X1574500Y587500D03*
X1571493D03*
X1562500Y583300D03*
Y586800D03*
X1568212Y587331D03*
X1577000Y610560D03*
Y607060D03*
X1573520Y607090D03*
Y610590D03*
X1577000Y613500D03*
Y617000D03*
X1574500Y591000D03*
X1571493D03*
X1539000Y591919D03*
Y595419D03*
X1573500Y617000D03*
Y613500D03*
X1568212Y590831D03*
X1542500Y591919D03*
Y595419D03*
X1530850Y603650D03*
Y607150D03*
X1649900Y81750D03*
Y85250D03*
X1643629Y83308D03*
Y86808D03*
X1614366Y87329D03*
Y90829D03*
X1636500Y87500D03*
Y91000D03*
X1628500Y90000D03*
Y86500D03*
X1625500Y86750D03*
Y90250D03*
X1598849Y90788D03*
Y87288D03*
X1602000Y87250D03*
Y90750D03*
X1643900Y70300D03*
Y73800D03*
X1650800Y70300D03*
Y73800D03*
X1647500Y70300D03*
Y73800D03*
X1595500Y87250D03*
Y90750D03*
X1592500Y90500D03*
Y87000D03*
X1621949Y83888D03*
Y87388D03*
X1618449Y83888D03*
Y87388D03*
X1605000Y76250D03*
Y79750D03*
X1617393Y41527D03*
Y45027D03*
X1613893Y41527D03*
Y45027D03*
X1595398Y39484D03*
Y42984D03*
X1598898Y39484D03*
Y42984D03*
X1604848Y39479D03*
Y42979D03*
X1608348Y39479D03*
Y42979D03*
X1647852Y189229D03*
Y192729D03*
X1650852D03*
Y189229D03*
X1630154Y214948D03*
Y211448D03*
X1606934Y191791D03*
Y188291D03*
X1603934Y192041D03*
Y188541D03*
X1612934Y191791D03*
Y188291D03*
X1609934Y191791D03*
Y188291D03*
X1639811Y191803D03*
Y188303D03*
X1596000Y187850D03*
Y184350D03*
X1599000Y187850D03*
Y184350D03*
X1618623Y191226D03*
Y187726D03*
X1621623Y191226D03*
Y187726D03*
X1624972Y192756D03*
Y189256D03*
X1636811Y191803D03*
Y188303D03*
X1645000Y217850D03*
X1630418Y192807D03*
Y189307D03*
X1633711Y192804D03*
Y189304D03*
X1645400Y228350D03*
Y224850D03*
X1599201Y249642D03*
Y253142D03*
X1605819Y259329D03*
Y262829D03*
X1591174Y227582D03*
Y231082D03*
X1645000Y221350D03*
X1591500Y329250D03*
Y325750D03*
X1648200Y336750D03*
Y340250D03*
X1645000Y336750D03*
Y340250D03*
X1645650Y345250D03*
Y348750D03*
X1648650D03*
Y345250D03*
X1624200Y403500D03*
X1622550Y358200D03*
Y354700D03*
X1616900Y403400D03*
X1620700D03*
X1616890Y399580D03*
Y396080D03*
X1633400Y372900D03*
Y369400D03*
X1594201Y384066D03*
Y387566D03*
X1594451Y398528D03*
Y395028D03*
X1620000Y349250D03*
Y345750D03*
X1649800Y452300D03*
Y448800D03*
X1627800Y464100D03*
X1643430Y434280D03*
Y437780D03*
X1624200Y407000D03*
X1606500Y405250D03*
Y408750D03*
X1609500D03*
Y405250D03*
X1616900Y406900D03*
X1620700D03*
X1643301Y418255D03*
Y414755D03*
X1622383Y492026D03*
Y495526D03*
X1627800Y467600D03*
X1631538Y530500D03*
Y534000D03*
X1628038Y530500D03*
Y534000D03*
X1621295Y533812D03*
Y530312D03*
X1624538Y534000D03*
Y530500D03*
X1656500Y86000D03*
Y89500D03*
X1653000Y81750D03*
Y85250D03*
X1708000Y59500D03*
Y56000D03*
X1711700Y62000D03*
Y58500D03*
X1705000Y56000D03*
Y59500D03*
X1663700Y87800D03*
Y84300D03*
X1711300Y65400D03*
Y68900D03*
X1667916Y58116D03*
Y54616D03*
X1704900Y69768D03*
Y66268D03*
X1654100Y70300D03*
Y73800D03*
X1705250Y48400D03*
Y44900D03*
X1700000Y102000D03*
Y105500D03*
X1696650Y102000D03*
Y105500D03*
X1706100Y128450D03*
Y124950D03*
X1676849Y189288D03*
Y192788D03*
X1679849Y189288D03*
Y192788D03*
X1667349Y189288D03*
Y192788D03*
X1659949Y189288D03*
Y192788D03*
X1664349Y189288D03*
Y192788D03*
X1703350Y174350D03*
Y177850D03*
X1710650Y166200D03*
Y169700D03*
X1683340Y177101D03*
Y180601D03*
X1653949Y189288D03*
Y192788D03*
X1656949Y189288D03*
Y192788D03*
X1662000Y328750D03*
Y332250D03*
X1656400Y336750D03*
Y340250D03*
X1657500Y462550D03*
X1661000D03*
X1656000Y451750D03*
Y448250D03*
X1659000Y451750D03*
Y448250D03*
X1657500Y466050D03*
X1661000D03*
X1693019Y514752D03*
Y518252D03*
X1690000Y518250D03*
Y514750D03*
X1702830Y512550D03*
Y509050D03*
X1718500Y79750D03*
Y83250D03*
X1722000Y73250D03*
Y76750D03*
X1714850Y74278D03*
Y77778D03*
X1729500Y54500D03*
Y51000D03*
X1726500Y54500D03*
Y51000D03*
X1723500D03*
Y54500D03*
X1762000Y76250D03*
Y79750D03*
X1714700Y58500D03*
Y62000D03*
X1718500Y72750D03*
Y76250D03*
X1758780Y92870D03*
X1755580D03*
X1765500Y76250D03*
Y79750D03*
X1773708Y109776D03*
Y113276D03*
X1758780Y96370D03*
X1755580D03*
X1714129Y173131D03*
Y169631D03*
X1724200Y510100D03*
Y506600D03*
X1715461Y587223D03*
Y590723D03*
X1833100Y4200D03*
Y7700D03*
X1829900Y80450D03*
Y83950D03*
X1824350Y88150D03*
Y91650D03*
X1833000Y83950D03*
Y80450D03*
X1824350Y94450D03*
X1793000Y149000D03*
Y152500D03*
X1819348Y145937D03*
Y149437D03*
X1815348D03*
Y145937D03*
X1802485Y136539D03*
Y140039D03*
X1804720Y106570D03*
Y103070D03*
X1808400Y117300D03*
Y120800D03*
X1811900Y117500D03*
Y121000D03*
X1787500Y152500D03*
Y149000D03*
X1780500Y109750D03*
Y113250D03*
X1822848Y145937D03*
Y149437D03*
X1811348Y145937D03*
Y149437D03*
X1824350Y97950D03*
X1777000Y109750D03*
Y113250D03*
X1786000Y158000D03*
Y161500D03*
X1836000Y158300D03*
Y161800D03*
X1834000Y532500D03*
Y529000D03*
X1782000Y588500D03*
Y585000D03*
X1780756Y576990D03*
Y573490D03*
X1835000Y586250D03*
Y582750D03*
Y575750D03*
Y579250D03*
X1787500Y595000D03*
Y591500D03*
X1884018Y45564D03*
Y49064D03*
X1880630Y45611D03*
Y49111D03*
X1886590Y69285D03*
Y72785D03*
X1890090Y69285D03*
Y72785D03*
X1883090Y69285D03*
Y72785D03*
X1842964Y104926D03*
Y101426D03*
X1859163Y141698D03*
Y145198D03*
X1866500Y144250D03*
Y140750D03*
X1875500Y147750D03*
Y144250D03*
X1878500Y147750D03*
Y144250D03*
X1881500Y147750D03*
Y144250D03*
X1870000D03*
Y140750D03*
X1839598Y101484D03*
Y104984D03*
X1897640Y140100D03*
Y136600D03*
X1862500Y153500D03*
Y150000D03*
X1856329Y107042D03*
Y103542D03*
X1881400Y189350D03*
Y192850D03*
X1897760Y202210D03*
Y198710D03*
X1881400Y181350D03*
Y177850D03*
X1842500Y169500D03*
Y166000D03*
X1875900Y158850D03*
Y162350D03*
Y168850D03*
Y165350D03*
X1840000Y526000D03*
Y522500D03*
X1839000Y513000D03*
Y509500D03*
X1838900Y502300D03*
Y498800D03*
X1881806Y588061D03*
X1840000Y532500D03*
Y529000D03*
X1862500Y574250D03*
Y577750D03*
Y586250D03*
Y582750D03*
X1868000Y584250D03*
Y580750D03*
X1862000Y566250D03*
Y569750D03*
X1871100Y586400D03*
X1873150Y561050D03*
Y557550D03*
X1876650Y561050D03*
Y557550D03*
X1881806Y591561D03*
X1871100Y589900D03*
X1922800Y90900D03*
Y87400D03*
X1925097Y115420D03*
Y111920D03*
X1916094Y103696D03*
Y107196D03*
X1931000Y150500D03*
Y147000D03*
X1916094Y110696D03*
Y107196D03*
X1912894Y107146D03*
Y110646D03*
Y107146D03*
Y103646D03*
X1921144Y115344D03*
Y118844D03*
Y115344D03*
Y111844D03*
X1921139Y105424D03*
Y108924D03*
X1900200Y130000D03*
Y133500D03*
Y123600D03*
Y127100D03*
X1928000Y195850D03*
Y199350D03*
X1922800Y196050D03*
Y199550D03*
X1919800Y196050D03*
Y199550D03*
X1937909Y183346D03*
Y186846D03*
X1941609D03*
Y183346D03*
X1914900Y201350D03*
Y197850D03*
X1911400Y201350D03*
Y197850D03*
X1918200Y548600D03*
Y545100D03*
G54D311*
X1899900Y206900D03*
X1898800Y195344D03*
G54D203*
X1404910Y536868D03*
Y538443D03*
Y540018D03*
Y541593D03*
Y543168D03*
Y544742D03*
Y546317D03*
Y547892D03*
Y549467D03*
Y551042D03*
X1548550Y598413D03*
Y599988D03*
Y601563D03*
Y603138D03*
Y604713D03*
Y606287D03*
Y607862D03*
Y609437D03*
Y611012D03*
Y612587D03*
G54D104*
X53953Y649705D03*
X242675Y649805D03*
X430143Y649535D03*
X617691Y649266D03*
X933345Y649255D03*
X1246843Y649285D03*
G54D122*
X663091Y147445D03*
X658091D03*
X653091D03*
X648091D03*
X663091Y152445D03*
X658091D03*
X653091D03*
X648091D03*
X663091Y157445D03*
X658091D03*
X653091D03*
X648091D03*
X663091Y162445D03*
X658091D03*
X653091D03*
X648091D03*
X663091Y167445D03*
X658091D03*
X653091D03*
X648091D03*
X663091Y172445D03*
X658091D03*
X653091D03*
X648091D03*
X663091Y429925D03*
X658091D03*
X653091D03*
X648091D03*
X663091Y434925D03*
X658091D03*
X653091D03*
X648091D03*
X663091Y439925D03*
X658091D03*
X653091D03*
X648091D03*
X663091Y444925D03*
X658091D03*
X653091D03*
X648091D03*
X663091Y449925D03*
X658091D03*
X653091D03*
X648091D03*
X663091Y454925D03*
X658091D03*
X653091D03*
X648091D03*
X688091Y147445D03*
X683091D03*
X678091D03*
X673091D03*
X668091D03*
X723091D03*
X718091D03*
X713091D03*
X708091D03*
X703091D03*
X698091D03*
X693091D03*
X688091Y152445D03*
X683091D03*
X678091D03*
X673091D03*
X668091D03*
X723091D03*
X718091D03*
X713091D03*
X708091D03*
X703091D03*
X698091D03*
X693091D03*
X688091Y157445D03*
X683091D03*
X678091D03*
X673091D03*
X668091D03*
X723091D03*
X718091D03*
X713091D03*
X708091D03*
X703091D03*
X698091D03*
X693091D03*
X688091Y162445D03*
X683091D03*
X678091D03*
X673091D03*
X668091D03*
X723091D03*
X718091D03*
X713091D03*
X708091D03*
X703091D03*
X698091D03*
X693091D03*
X688091Y167445D03*
X683091D03*
X678091D03*
X673091D03*
X668091D03*
X723091D03*
X718091D03*
X713091D03*
X708091D03*
X703091D03*
X698091D03*
X693091D03*
X688091Y172445D03*
X683091D03*
X678091D03*
X673091D03*
X668091D03*
X723091D03*
X718091D03*
X713091D03*
X708091D03*
X703091D03*
X698091D03*
X693091D03*
X688091Y429925D03*
X683091D03*
X678091D03*
X673091D03*
X668091D03*
X723091D03*
X718091D03*
X713091D03*
X708091D03*
X703091D03*
X698091D03*
X693091D03*
X688091Y434925D03*
X683091D03*
X678091D03*
X673091D03*
X668091D03*
X723091D03*
X718091D03*
X713091D03*
X708091D03*
X703091D03*
X698091D03*
X693091D03*
X688091Y439925D03*
X683091D03*
X678091D03*
X673091D03*
X668091D03*
X723091D03*
X718091D03*
X713091D03*
X708091D03*
X703091D03*
X698091D03*
X693091D03*
X688091Y444925D03*
X683091D03*
X678091D03*
X673091D03*
X668091D03*
X723091D03*
X718091D03*
X713091D03*
X708091D03*
X703091D03*
X698091D03*
X693091D03*
X688091Y449925D03*
X683091D03*
X678091D03*
X673091D03*
X668091D03*
X723091D03*
X718091D03*
X713091D03*
X708091D03*
X703091D03*
X698091D03*
X693091D03*
X688091Y454925D03*
X683091D03*
X678091D03*
X673091D03*
X668091D03*
X723091D03*
X718091D03*
X713091D03*
X708091D03*
X703091D03*
X698091D03*
X693091D03*
X743091Y147445D03*
X738091D03*
X733091D03*
X728091D03*
X743091Y152445D03*
X738091D03*
X733091D03*
X728091D03*
X743091Y157445D03*
X738091D03*
X733091D03*
X728091D03*
X743091Y162445D03*
X738091D03*
X733091D03*
X728091D03*
X743091Y167445D03*
X738091D03*
X733091D03*
X728091D03*
X743091Y172445D03*
X738091D03*
X733091D03*
X728091D03*
X743091Y429925D03*
X738091D03*
X733091D03*
X728091D03*
X743091Y434925D03*
X738091D03*
X733091D03*
X728091D03*
X743091Y439925D03*
X738091D03*
X733091D03*
X728091D03*
X743091Y444925D03*
X738091D03*
X733091D03*
X728091D03*
X743091Y449925D03*
X738091D03*
X733091D03*
X728091D03*
X743091Y454925D03*
X738091D03*
X733091D03*
X728091D03*
X1337618Y147445D03*
X1332618D03*
X1327618D03*
X1322618D03*
X1317618D03*
X1312618D03*
X1307618D03*
X1302618D03*
X1342618D03*
X1297618D03*
X1337618Y152445D03*
X1332618D03*
X1327618D03*
X1322618D03*
X1317618D03*
X1312618D03*
X1307618D03*
X1302618D03*
X1342618D03*
X1297618D03*
X1337618Y157445D03*
X1332618D03*
X1327618D03*
X1322618D03*
X1317618D03*
X1312618D03*
X1307618D03*
X1302618D03*
X1342618D03*
X1297618D03*
X1337618Y162445D03*
X1332618D03*
X1327618D03*
X1322618D03*
X1317618D03*
X1312618D03*
X1307618D03*
X1302618D03*
X1342618D03*
X1297618D03*
X1337618Y167445D03*
X1332618D03*
X1327618D03*
X1322618D03*
X1317618D03*
X1312618D03*
X1307618D03*
X1302618D03*
X1342618D03*
X1297618D03*
X1337618Y172445D03*
X1332618D03*
X1327618D03*
X1322618D03*
X1317618D03*
X1312618D03*
X1307618D03*
X1302618D03*
X1342618D03*
X1297618D03*
X1337618Y429925D03*
X1332618D03*
X1327618D03*
X1322618D03*
X1317618D03*
X1312618D03*
X1307618D03*
X1302618D03*
X1342618D03*
X1297618D03*
X1337618Y434925D03*
X1332618D03*
X1327618D03*
X1322618D03*
X1317618D03*
X1312618D03*
X1307618D03*
X1302618D03*
X1342618D03*
X1297618D03*
X1337618Y439925D03*
X1332618D03*
X1327618D03*
X1322618D03*
X1317618D03*
X1312618D03*
X1307618D03*
X1302618D03*
X1342618D03*
X1297618D03*
X1337618Y444925D03*
X1332618D03*
X1327618D03*
X1322618D03*
X1317618D03*
X1312618D03*
X1307618D03*
X1302618D03*
X1342618D03*
X1297618D03*
X1337618Y449925D03*
X1332618D03*
X1327618D03*
X1322618D03*
X1317618D03*
X1312618D03*
X1307618D03*
X1302618D03*
X1342618D03*
X1297618D03*
X1337618Y454925D03*
X1332618D03*
X1327618D03*
X1322618D03*
X1317618D03*
X1312618D03*
X1307618D03*
X1302618D03*
X1342618D03*
X1297618D03*
X1392618Y147445D03*
X1387618D03*
X1382618D03*
X1377618D03*
X1372618D03*
X1367618D03*
X1362618D03*
X1357618D03*
X1352618D03*
X1347618D03*
X1392618Y152445D03*
X1387618D03*
X1382618D03*
X1377618D03*
X1372618D03*
X1367618D03*
X1362618D03*
X1357618D03*
X1352618D03*
X1347618D03*
X1392618Y157445D03*
X1387618D03*
X1382618D03*
X1377618D03*
X1372618D03*
X1367618D03*
X1362618D03*
X1357618D03*
X1352618D03*
X1347618D03*
X1392618Y162445D03*
X1387618D03*
X1382618D03*
X1377618D03*
X1372618D03*
X1367618D03*
X1362618D03*
X1357618D03*
X1352618D03*
X1347618D03*
X1392618Y167445D03*
X1387618D03*
X1382618D03*
X1377618D03*
X1372618D03*
X1367618D03*
X1362618D03*
X1357618D03*
X1352618D03*
X1347618D03*
X1392618Y172445D03*
X1387618D03*
X1382618D03*
X1377618D03*
X1372618D03*
X1367618D03*
X1362618D03*
X1357618D03*
X1352618D03*
X1347618D03*
X1392618Y429925D03*
X1387618D03*
X1382618D03*
X1377618D03*
X1372618D03*
X1367618D03*
X1362618D03*
X1357618D03*
X1352618D03*
X1347618D03*
X1392618Y434925D03*
X1387618D03*
X1382618D03*
X1377618D03*
X1372618D03*
X1367618D03*
X1362618D03*
X1357618D03*
X1352618D03*
X1347618D03*
X1392618Y439925D03*
X1387618D03*
X1382618D03*
X1377618D03*
X1372618D03*
X1367618D03*
X1362618D03*
X1357618D03*
X1352618D03*
X1347618D03*
X1392618Y444925D03*
X1387618D03*
X1382618D03*
X1377618D03*
X1372618D03*
X1367618D03*
X1362618D03*
X1357618D03*
X1352618D03*
X1347618D03*
X1392618Y449925D03*
X1387618D03*
X1382618D03*
X1377618D03*
X1372618D03*
X1367618D03*
X1362618D03*
X1357618D03*
X1352618D03*
X1347618D03*
X1392618Y454925D03*
X1387618D03*
X1382618D03*
X1377618D03*
X1372618D03*
X1367618D03*
X1362618D03*
X1357618D03*
X1352618D03*
X1347618D03*
G54D11*
X-16420Y27510D03*
X-16320Y42550D03*
X-6380Y27510D03*
X-6280Y42550D03*
G54D302*
X1938249Y80902D03*
G54D140*
X694053Y213901D03*
X1359142Y-6923D03*
X1359453Y25101D03*
X1361760Y383969D03*
X1363453Y571957D03*
Y603157D03*
G54D222*
X1478330Y608784D03*
X1513868Y610052D03*
G54D150*
X1279928Y207308D03*
X1288111Y199713D03*
G54D12*
X-13406Y73511D03*
Y59763D03*
X1427533Y572491D03*
Y586239D03*
G54D303*
X1943369Y80902D03*
G54D132*
X724937Y-652D03*
X722968D03*
X721000D03*
X719031D03*
X717063D03*
Y10652D03*
X719031D03*
X721000D03*
X722968D03*
X724937D03*
X723980Y584050D03*
X722012D03*
X720043D03*
X718075D03*
X716106D03*
Y595354D03*
X718075D03*
X720043D03*
X722012D03*
X723980D03*
X1587610Y582396D03*
X1585641D03*
X1583673D03*
X1581704D03*
Y593700D03*
X1583673D03*
X1585641D03*
X1587610D03*
X1589578Y582396D03*
Y593700D03*
X1850700Y150348D03*
X1848732D03*
X1846763D03*
X1854637D03*
X1852669D03*
X1848732Y161652D03*
X1850700D03*
X1852669D03*
X1846763D03*
X1854637D03*
G54D312*
X1952250Y240355D03*
G54D231*
X1550750Y270437D03*
Y268469D03*
Y266500D03*
Y264531D03*
Y262563D03*
X1537250D03*
Y264531D03*
Y266500D03*
Y268469D03*
Y270437D03*
G54D240*
X1625951Y340193D03*
X1639055D03*
Y346099D03*
X1625951D03*
G54D321*
X1960433Y213997D03*
Y235451D03*
G54D21*
X-16000Y534300D03*
Y570300D03*
X21652Y8515D03*
X25152D03*
X25558Y-8431D03*
X22058D03*
X46550Y20464D03*
X31907Y-19337D03*
X35407D03*
X31899Y-14906D03*
X35399D03*
X31599Y17909D03*
X28099D03*
X9100Y22344D03*
X12600D03*
X20100D03*
X16600D03*
X28099Y14409D03*
X31599D03*
X45113Y-16137D03*
X20411Y50456D03*
X16911D03*
X-1000Y78900D03*
X2500D03*
X21347Y81785D03*
X17847D03*
X9823Y53541D03*
X13323D03*
X20425Y53711D03*
X16925D03*
X2200Y75650D03*
X-1300D03*
X2170Y51080D03*
X5670D03*
X4742Y270027D03*
X1242D03*
X9450Y451000D03*
X5950D03*
X33678Y426855D03*
X30178D03*
X30305Y436582D03*
X33805D03*
X28500Y500500D03*
X25000D03*
X-569Y488479D03*
X-4069D03*
X6353Y488492D03*
X2853D03*
X28500Y492500D03*
X25000D03*
X-13400Y499300D03*
X-9900D03*
X-13400Y502800D03*
X-9900D03*
X-10500Y506300D03*
X-14000D03*
X-10500Y512300D03*
X-14000D03*
X-10500Y509300D03*
X-14000D03*
X28500Y496500D03*
X25000D03*
X-1093Y467071D03*
X2407D03*
X-12500Y534300D03*
Y570300D03*
X10200Y528800D03*
X6700D03*
X0D03*
X3500D03*
X-7746Y587765D03*
X-11246D03*
X10780Y559064D03*
X7280D03*
X-4800Y564000D03*
X-8300D03*
X-1000D03*
X2500D03*
X10000D03*
X6500D03*
X30422Y562532D03*
X33922D03*
X24265Y529069D03*
X27765D03*
X-3800Y528800D03*
X-7300D03*
X-7483Y551374D03*
X-10983D03*
X-10842Y554878D03*
X-7342D03*
X8678Y593224D03*
X5178D03*
X-9785Y590965D03*
X-6285D03*
X53704Y8216D03*
X57204D03*
X50050Y20464D03*
X63712Y2888D03*
X60212D03*
X57204Y4716D03*
X53704D03*
X58389Y-13808D03*
X54889D03*
X58389Y-10601D03*
X54889D03*
X48613Y-16137D03*
X58200Y95000D03*
X54700D03*
X58200Y91500D03*
X54700D03*
X101000Y118000D03*
X104500D03*
Y121500D03*
X101000D03*
X52100Y148500D03*
X55600D03*
X58200Y105500D03*
X54700D03*
X58200Y112500D03*
X54700D03*
X58200Y116000D03*
X54700D03*
X58200Y140500D03*
X54700D03*
X58200Y133500D03*
X54700D03*
X58200Y137000D03*
X54700D03*
X58200Y144000D03*
X54700D03*
X58200Y126500D03*
X54700D03*
X58200Y123000D03*
X54700D03*
X58200Y130000D03*
X54700D03*
X58200Y119500D03*
X54700D03*
X58200Y109000D03*
X54700D03*
X58200Y102000D03*
X54700D03*
X58200Y98500D03*
X54700D03*
X72700Y171900D03*
X69200D03*
X48300Y157500D03*
X51800D03*
X91600Y162300D03*
X95100D03*
X63600Y163400D03*
X67100D03*
X56500Y200500D03*
X53000D03*
X56500Y204000D03*
X53000D03*
X94250Y267122D03*
X90750D03*
X94278Y270852D03*
X90778D03*
X93700Y262300D03*
X97200D03*
X62500Y275500D03*
X66000D03*
X59500D03*
X56000D03*
X93858Y240300D03*
X97358D03*
X106698Y219572D03*
X108462Y316200D03*
X98500Y298500D03*
X102000D03*
X55500Y334500D03*
X59000D03*
X91000Y297000D03*
X87500D03*
Y300500D03*
X91000D03*
X87500Y289000D03*
X91000D03*
Y285300D03*
X87500D03*
Y293500D03*
X91000D03*
X87500Y313500D03*
X91000D03*
X87500Y309500D03*
X91000D03*
Y306000D03*
X87500D03*
X73000Y324500D03*
X76500D03*
X55500Y323500D03*
X59000D03*
Y327000D03*
X55500D03*
X84650Y338700D03*
X81150D03*
X59000Y280500D03*
X62500D03*
X91000Y282200D03*
X87500D03*
X81700Y343900D03*
X85200D03*
X58000Y351500D03*
X54500D03*
Y348400D03*
X58000D03*
X68500Y388600D03*
X72000D03*
X61300Y392100D03*
X57800D03*
X54500Y354600D03*
X58000D03*
X85200Y347000D03*
X81700D03*
X68500Y385500D03*
X72000D03*
X61000Y385400D03*
X64500D03*
X59900Y388600D03*
X63400D03*
X74648Y461201D03*
X71148D03*
X78100Y465511D03*
X74600D03*
X123892Y13078D03*
X120392D03*
X123892Y50878D03*
X120392D03*
X123907Y87248D03*
X120407D03*
X159700Y199100D03*
X156200D03*
X159700Y195600D03*
X156200D03*
X123100Y209200D03*
X126600D03*
X120179Y210345D03*
X116679D03*
X134124Y209533D03*
X130624D03*
X150400Y208300D03*
X153900D03*
X110088Y252322D03*
X113588D03*
X110198Y219572D03*
X133924Y273300D03*
X130424D03*
X124124Y272533D03*
X127624D03*
X117000Y263500D03*
X113500D03*
X113100Y266763D03*
X116600D03*
X133788Y269786D03*
X130288D03*
X153200Y272900D03*
X156700D03*
X113100Y234713D03*
X116600D03*
X134324Y241333D03*
X130824D03*
X116900Y231450D03*
X113400D03*
X134378Y237702D03*
X130878D03*
X120177Y242977D03*
X116677D03*
X123624Y240533D03*
X127124D03*
X149710Y240512D03*
X153210D03*
X110817Y283595D03*
X114317D03*
X111962Y316200D03*
X113299Y295373D03*
X109799D03*
X111000Y301000D03*
X114500D03*
X134250Y302000D03*
X130750D03*
X134519Y337550D03*
X131019D03*
X121519Y336550D03*
X125019D03*
X134250Y334000D03*
X130750D03*
X113100Y330563D03*
X116600D03*
X123624Y304533D03*
X127124D03*
X134124Y305533D03*
X130624D03*
X117000Y327300D03*
X113500D03*
X150600Y306100D03*
X154100D03*
X116995Y338517D03*
X113495D03*
X149909Y337400D03*
X153409D03*
X109866Y348586D03*
X113366D03*
X113200Y402500D03*
X116700D03*
X110120Y378710D03*
X113620D03*
X114500Y360500D03*
X111000D03*
Y363700D03*
X114500D03*
X134250Y365900D03*
X130750D03*
X123871Y368603D03*
X127371D03*
X134369Y369241D03*
X130869D03*
X147710Y369400D03*
X151210D03*
X117020Y392130D03*
X113520D03*
X132111Y402698D03*
X128611D03*
X132131Y399498D03*
X128631D03*
X151343Y418959D03*
X154843D03*
X151314Y422658D03*
X154814D03*
X163375Y404446D03*
X159875D03*
X163375Y407446D03*
X159875D03*
X116600Y414700D03*
X113100D03*
X116600Y411700D03*
X113100D03*
X116700Y408600D03*
X113200D03*
X116700Y405500D03*
X113200D03*
X123792Y507300D03*
X120292D03*
X123492Y551400D03*
X119992D03*
X123692Y589200D03*
X120192D03*
X449100Y273300D03*
X445600D03*
X432000Y268000D03*
X428500D03*
X461500Y300500D03*
X458000D03*
X461400Y287500D03*
X457900D03*
X461400Y290500D03*
X457900D03*
X457248Y281341D03*
X460748D03*
X458000Y303500D03*
X461500D03*
Y297500D03*
X458000D03*
X461400Y284500D03*
X457900D03*
X461300Y293700D03*
X457800D03*
X595500Y102000D03*
X599000D03*
X655500Y25500D03*
X652000D03*
X660893Y35488D03*
X657393D03*
X607500Y120200D03*
X611000D03*
Y113700D03*
X607500D03*
X611000Y116700D03*
X607500D03*
Y110200D03*
X611000D03*
X661005Y134450D03*
X657505D03*
X661005Y137650D03*
X657505D03*
X640566Y278324D03*
X644066D03*
X649500Y275300D03*
X646000D03*
Y265000D03*
X649500D03*
Y272000D03*
X646000D03*
X650000Y268300D03*
X646500D03*
X636800Y262500D03*
X640300D03*
X640500Y302000D03*
X644000D03*
X640500Y322000D03*
X644000D03*
X640500Y327000D03*
X644000D03*
X640500Y337000D03*
X644000D03*
X640500Y332000D03*
X644000D03*
X640500Y317000D03*
X644000D03*
X640500Y307000D03*
X644000D03*
X640500Y312000D03*
X644000D03*
X625500Y469159D03*
X622000D03*
X616300Y466000D03*
X612800D03*
X615834Y469559D03*
X612334D03*
X616034Y472759D03*
X612534D03*
X625500D03*
X622000D03*
X632930Y492550D03*
X629430D03*
X625430D03*
X621930D03*
X655900Y587500D03*
X659400D03*
X659500Y591500D03*
X656000D03*
X683900Y21500D03*
X687400D03*
X673850Y27300D03*
X677350D03*
X687000Y14500D03*
X683500D03*
X687000Y11000D03*
X683500D03*
X696750Y31000D03*
X693250D03*
X679300Y30800D03*
X675800D03*
X686900Y17900D03*
X683400D03*
X679300Y34200D03*
X675800D03*
X667650Y34500D03*
X664150D03*
X698137Y69515D03*
X694637D03*
X696750Y34500D03*
X693250D03*
X688416Y69515D03*
X684916D03*
X718000Y203100D03*
X714500D03*
X714400Y207050D03*
X717900D03*
X722300Y218100D03*
X718800D03*
X697267Y200989D03*
X700767D03*
X684050Y278000D03*
X687550D03*
X687520Y257570D03*
X684020D03*
X687500Y251307D03*
X684000D03*
X703700Y258900D03*
X707200D03*
X688250Y264000D03*
X684750D03*
X684050Y260597D03*
X687550D03*
X707000Y262000D03*
X703500D03*
Y265500D03*
X707000D03*
X687550Y274500D03*
X684050D03*
X688250Y271000D03*
X684750D03*
X688250Y267500D03*
X684750D03*
X712300Y227500D03*
X715800D03*
X709000Y229000D03*
X705500D03*
X698000D03*
X701500D03*
X673713Y227609D03*
X670213D03*
X687500Y254470D03*
X684000D03*
X694000Y305500D03*
X690500D03*
X694000Y300500D03*
X690500D03*
X694000Y330500D03*
X690500D03*
X694000Y335500D03*
X690500D03*
X694000Y325500D03*
X690500D03*
X713050Y304375D03*
X709550D03*
X717300Y300700D03*
X720800D03*
X694000Y320500D03*
X690500D03*
X701000Y315500D03*
X697500D03*
X701000Y310500D03*
X697500D03*
X687556Y295292D03*
X684056D03*
X677124Y295168D03*
X680624D03*
X709550Y301275D03*
X713050D03*
X717300Y297500D03*
X720800D03*
X709550Y297975D03*
X713050D03*
X706662Y287275D03*
X710162D03*
X706662Y290775D03*
X710162D03*
X669200Y295000D03*
X665700D03*
X669000Y290200D03*
X665500D03*
X678772Y359140D03*
X682272D03*
X682150Y521600D03*
X678650D03*
X675250Y512500D03*
X671750D03*
X696750Y521000D03*
X693250D03*
X696750Y517000D03*
X693250D03*
X697500Y555750D03*
X694000D03*
X708155Y567556D03*
X704655D03*
X708153Y570862D03*
X704653D03*
X686500Y587800D03*
X690000D03*
X689500Y555750D03*
X686000D03*
X686500Y578500D03*
X683000D03*
X686599Y573493D03*
X683099D03*
X689950Y591000D03*
X686450D03*
X674380Y591560D03*
X677880D03*
X773500Y13078D03*
X770000D03*
X773500Y50878D03*
X770000D03*
X773500Y89000D03*
X770000D03*
X772732Y209533D03*
X776232D03*
X783732D03*
X780232D03*
X736000Y250500D03*
X739500D03*
X783115Y269655D03*
X779615D03*
X772519Y272931D03*
X776019D03*
X767000Y264400D03*
X763500D03*
X763232Y267610D03*
X766732D03*
X783485Y240623D03*
X779985D03*
X784358Y237423D03*
X780858D03*
X772351Y240966D03*
X775851D03*
X737000Y255000D03*
X733500D03*
X763250Y235500D03*
X766750D03*
X766800Y232000D03*
X763300D03*
X783045Y272906D03*
X779545D03*
X758917Y316392D03*
X762417D03*
X737750Y292500D03*
X741250D03*
X772870Y304000D03*
X776370D03*
X783211Y301964D03*
X779711D03*
X766900Y295800D03*
X763400D03*
X763232Y299033D03*
X766732D03*
X772732Y337533D03*
X776232D03*
X766250Y327608D03*
X762750D03*
X763200Y331900D03*
X766700D03*
X783286Y305173D03*
X779786D03*
X784765Y334046D03*
X781265D03*
X783732Y337533D03*
X780232D03*
X758952Y380738D03*
X762452D03*
X783194Y366012D03*
X779694D03*
X783182Y369533D03*
X779682D03*
X772982Y369033D03*
X776482D03*
X766800Y359800D03*
X763300D03*
X763232Y363033D03*
X766732D03*
X766300Y393400D03*
X762800D03*
X784486Y401784D03*
X780986D03*
X784520Y398509D03*
X781020D03*
X773400Y512800D03*
X769900D03*
X773100Y551400D03*
X769600D03*
X773300Y589200D03*
X769800D03*
X810700Y195600D03*
X807200D03*
X810700Y199100D03*
X807200D03*
X799850Y207600D03*
X803350D03*
X803100Y241000D03*
X806600D03*
X802100Y273000D03*
X805600D03*
X801300Y305000D03*
X804800D03*
X801800Y336400D03*
X805300D03*
X802208Y367560D03*
X805708D03*
X807000Y420000D03*
X803500D03*
X807000Y417000D03*
X803500D03*
X815500Y404000D03*
X812000D03*
X815500Y407500D03*
X812000D03*
X1081700Y268000D03*
X1078200D03*
X1105175Y277317D03*
X1101675D03*
X1107000Y302500D03*
X1110500D03*
Y284500D03*
X1107000D03*
X1110500Y295000D03*
X1107000D03*
X1110500Y299000D03*
X1107000D03*
X1110500Y288000D03*
X1107000D03*
X1110500Y291500D03*
X1107000D03*
X1106856Y281341D03*
X1110356D03*
X1109840Y322680D03*
X1106340D03*
X1267100Y134500D03*
X1270600D03*
X1274500Y138000D03*
X1278000D03*
Y141000D03*
X1274500D03*
X1255400Y113917D03*
X1251900D03*
X1255400Y116917D03*
X1251900D03*
Y110417D03*
X1255400D03*
X1251900Y120417D03*
X1255400D03*
X1278000Y134500D03*
X1274500D03*
X1267100Y138000D03*
X1270600D03*
X1246970Y137547D03*
X1250470D03*
X1254400Y125400D03*
X1250900D03*
X1268250Y461504D03*
X1271750D03*
X1275250D03*
X1271750D03*
X1277750Y482500D03*
Y479000D03*
Y474000D03*
Y487500D03*
X1268250Y466204D03*
X1271750D03*
X1275250D03*
X1271750D03*
X1274250Y474000D03*
X1277750D03*
X1274250Y479000D03*
X1277750D03*
X1274250Y482500D03*
X1277750D03*
X1274250Y487500D03*
X1277750D03*
X1258750Y490500D03*
X1262250D03*
X1265750D03*
X1262250D03*
X1258750Y485500D03*
X1262250D03*
X1265750D03*
X1262250D03*
X1260930Y474540D03*
X1264430D03*
X1260930Y469540D03*
X1264430D03*
X1267930Y474540D03*
X1264430D03*
X1267930Y469540D03*
X1264430D03*
X1340090Y7970D03*
X1330500Y80800D03*
X1334000D03*
X1340000Y86500D03*
X1336500D03*
X1334000Y77800D03*
X1330500D03*
X1334000Y68000D03*
X1330500D03*
X1334000Y55000D03*
X1330500D03*
Y64500D03*
X1334000D03*
X1330500Y61000D03*
X1334000D03*
X1317384Y81896D03*
X1313884D03*
X1319000Y95000D03*
X1315500D03*
X1325500D03*
X1322000D03*
X1332000Y95100D03*
X1328500D03*
X1336500Y83500D03*
X1340000D03*
X1334000Y74500D03*
X1330500D03*
X1334000Y71500D03*
X1330500D03*
X1334000Y58000D03*
X1330500D03*
X1333500Y40700D03*
X1330000D03*
X1330500Y51900D03*
X1334000D03*
X1341757Y96489D03*
X1340800Y413500D03*
X1337300D03*
X1342500Y419000D03*
X1314086Y462030D03*
X1310586D03*
X1307086D03*
X1310586D03*
X1332022Y464337D03*
X1335522D03*
X1339022D03*
X1335522D03*
X1338508Y510187D03*
X1335008D03*
X1330750Y501000D03*
X1327250D03*
X1307130Y466600D03*
X1310630D03*
X1314130D03*
X1310630D03*
X1332022Y469337D03*
X1335522D03*
X1281250Y482500D03*
Y479000D03*
Y474000D03*
Y487500D03*
X1339022Y469337D03*
X1335522D03*
X1324863Y477492D03*
X1328363D03*
X1324963Y472592D03*
X1328463D03*
X1331863Y477492D03*
X1328363D03*
X1331963Y472592D03*
X1328463D03*
X1341000Y540050D03*
X1343590Y7970D03*
X1372989Y8876D03*
X1369489D03*
X1363089Y8376D03*
X1366589D03*
X1362985Y11633D03*
X1366485D03*
X1381458Y-13901D03*
X1384958D03*
X1362273Y-20349D03*
X1365773D03*
X1386727Y4966D03*
X1383227D03*
X1382934Y-17458D03*
X1379434D03*
X1349944Y46449D03*
X1346444D03*
X1378000Y58500D03*
X1374500D03*
X1378000Y50500D03*
X1374500D03*
X1384300Y43900D03*
X1387800D03*
X1353040Y85780D03*
X1349540D03*
X1357000Y92340D03*
X1353500D03*
X1357000Y89140D03*
X1353500D03*
X1374400Y40200D03*
X1370900D03*
X1363400D03*
X1366900D03*
X1378000Y54500D03*
X1374500D03*
X1370820Y43895D03*
X1374320D03*
X1345257Y96489D03*
X1357700Y129450D03*
X1354200D03*
X1349700D03*
X1346200D03*
X1393200Y391745D03*
X1389700D03*
X1386100Y372776D03*
X1382600D03*
X1365000Y369139D03*
X1368500D03*
X1350800Y370500D03*
X1347300D03*
X1382933Y375976D03*
X1386433D03*
X1376200Y399100D03*
X1372700D03*
X1365707Y399068D03*
X1369207D03*
X1392200Y394845D03*
X1388700D03*
X1398280Y388701D03*
X1394780D03*
X1346000Y419000D03*
X1358000Y501800D03*
X1354500D03*
X1351700Y502200D03*
X1348200D03*
X1366500Y500500D03*
X1363000D03*
X1351700Y499000D03*
X1348200D03*
X1388986Y578365D03*
X1385486D03*
X1352500Y540050D03*
X1349000D03*
X1380420Y548730D03*
X1383920D03*
X1344500Y540050D03*
X1366484Y553447D03*
X1369984D03*
X1366534Y556907D03*
X1370034D03*
X1385317Y564894D03*
X1388817D03*
X1381685Y585222D03*
X1385185D03*
X1378400Y587056D03*
X1374900D03*
X1367400D03*
X1370900D03*
X1393735Y551044D03*
X1397235D03*
X1386250Y595500D03*
X1389750D03*
X1366791Y590313D03*
X1370291D03*
X1368200Y619200D03*
X1371700D03*
X1378200D03*
X1374700D03*
X1389750Y592000D03*
X1386250D03*
X1460631Y252416D03*
X1457131D03*
X1448839Y255160D03*
X1445339D03*
X1454500Y373000D03*
X1451000D03*
X1457569Y414166D03*
X1454069D03*
X1457569Y410666D03*
X1454069D03*
X1454500Y448000D03*
X1451000D03*
X1439000Y442500D03*
X1435500D03*
X1454500Y437000D03*
X1451000D03*
X1454500Y442500D03*
X1451000D03*
X1439000Y437000D03*
X1435500D03*
X1439000Y448000D03*
X1435500D03*
X1439000Y453500D03*
X1435500D03*
X1454500Y431500D03*
X1451000D03*
X1456100Y503000D03*
X1459600D03*
X1456100Y506000D03*
X1459600D03*
Y509000D03*
X1456100D03*
X1436060Y544955D03*
X1432560D03*
X1423140Y559233D03*
X1426640D03*
X1416272Y559180D03*
X1419772D03*
X1436000Y551500D03*
X1432500D03*
X1436100Y538400D03*
X1432600D03*
X1432560Y541455D03*
X1436060D03*
Y548455D03*
X1432560D03*
X1436100Y535400D03*
X1432600D03*
X1465400Y621700D03*
X1516600Y-6500D03*
X1520100D03*
X1525000D03*
X1512500D03*
X1509000D03*
X1489800Y115088D03*
X1493300D03*
X1489800Y120588D03*
X1493300D03*
X1489800Y115088D03*
X1486300D03*
X1492692Y127250D03*
X1489192D03*
X1489800Y120588D03*
X1486300D03*
X1492692Y127250D03*
X1496192D03*
X1492692Y132750D03*
X1489192D03*
X1492692D03*
X1496192D03*
X1520100Y200200D03*
X1516600D03*
X1492548Y215132D03*
X1489048D03*
X1507446Y221770D03*
X1503946D03*
X1524250Y314300D03*
X1520750D03*
X1523250Y338500D03*
X1519750D03*
X1511955Y310641D03*
X1508455D03*
X1511955Y307641D03*
X1508455D03*
X1512733Y295817D03*
X1509233D03*
X1503226Y623027D03*
X1506726D03*
X1474900Y622900D03*
X1478400D03*
X1468900Y621700D03*
X1576800Y-6800D03*
X1573300D03*
X1551300Y-6200D03*
X1547800D03*
X1554300D03*
X1557800D03*
X1589000Y-12600D03*
X1570300Y-6800D03*
X1566800D03*
X1577398Y-3069D03*
X1573898D03*
X1589000Y-16100D03*
X1528500Y-6500D03*
X1533000D03*
X1536500D03*
X1577398Y3931D03*
X1573898D03*
Y431D03*
X1577398D03*
X1584099Y146538D03*
X1580599D03*
X1584099Y143538D03*
X1580599D03*
X1585750Y149600D03*
X1582250D03*
X1573892Y134959D03*
X1570392D03*
X1585000Y135538D03*
X1581500D03*
X1581810Y132538D03*
X1585310D03*
X1581810Y129538D03*
X1585310D03*
X1575910Y120760D03*
X1579410D03*
X1570374Y140959D03*
X1573874D03*
Y143959D03*
X1570374D03*
X1570354Y137959D03*
X1573854D03*
X1578200Y215770D03*
X1581700D03*
X1578200Y210770D03*
X1581700D03*
X1588701Y172162D03*
X1585201D03*
X1588599Y169038D03*
X1585099D03*
X1588501Y161362D03*
X1585001D03*
X1588599Y164538D03*
X1585099D03*
X1585750Y189000D03*
X1582250D03*
X1585750Y194500D03*
X1582250D03*
X1571036Y159073D03*
X1574536D03*
X1549899Y255747D03*
X1546399D03*
X1557500Y260400D03*
X1561000D03*
X1546399Y252647D03*
X1549899D03*
X1528250Y314300D03*
X1531750D03*
X1557250Y298500D03*
X1553750D03*
X1557525Y308909D03*
X1554025D03*
X1557250Y305500D03*
X1553750D03*
X1557250Y301500D03*
X1553750D03*
X1583559Y321059D03*
X1587059D03*
X1528250Y317400D03*
X1531750D03*
X1536728Y322466D03*
X1533228D03*
X1557250Y312500D03*
X1553750D03*
X1566850Y344350D03*
X1570350D03*
X1566454Y620727D03*
X1569954D03*
X1557583Y620894D03*
X1561083D03*
X1541211Y604235D03*
X1537711D03*
X1539000Y610500D03*
X1542500D03*
X1575790Y597340D03*
X1579290D03*
X1575790Y601040D03*
X1579290D03*
X1534967Y616500D03*
X1531467D03*
X1538060Y598459D03*
X1541560D03*
X1530385Y620053D03*
X1533885D03*
X1592500Y-12600D03*
Y-16100D03*
X1608750Y90500D03*
X1605250D03*
X1627500Y72500D03*
X1624000D03*
X1621599Y90538D03*
X1618099D03*
X1627100Y197580D03*
X1623600D03*
X1602250Y197000D03*
X1598750D03*
X1614250D03*
X1610750D03*
X1645250Y252500D03*
X1641750D03*
X1641350Y231500D03*
X1644850D03*
X1641750Y255500D03*
X1645250D03*
X1604400Y242600D03*
X1600900D03*
X1605650Y246500D03*
X1602150D03*
Y249500D03*
X1605650D03*
Y252500D03*
X1602150D03*
X1615064Y222460D03*
X1618564D03*
X1605650Y255500D03*
X1602150D03*
X1618564Y225460D03*
X1615064D03*
X1644500Y325000D03*
X1641000D03*
Y328500D03*
X1644500D03*
X1594750Y402000D03*
X1598250D03*
X1638500Y398700D03*
X1635000D03*
X1620700Y391100D03*
X1617200D03*
X1645300Y361350D03*
X1648800D03*
X1645300Y364850D03*
X1648800D03*
X1601829Y379923D03*
X1605329D03*
X1601829Y376723D03*
X1605329D03*
X1623750Y446500D03*
X1627250D03*
X1609250Y451000D03*
X1605750D03*
X1605669Y454809D03*
X1609169D03*
X1627300Y439500D03*
X1623800D03*
X1616300Y450000D03*
X1612800D03*
X1615300Y459100D03*
X1611800D03*
X1605750Y446000D03*
X1609250D03*
X1633250Y449500D03*
X1636750D03*
X1627300Y453663D03*
X1623800D03*
X1636700Y445800D03*
X1633200D03*
X1633250Y452500D03*
X1636750D03*
X1623750Y443500D03*
X1627250D03*
X1635700Y441900D03*
X1632200D03*
X1614750Y442500D03*
X1618250D03*
X1614750Y439500D03*
X1618250D03*
X1594000Y455500D03*
X1590500D03*
X1597800Y408400D03*
X1601300D03*
X1601250Y416000D03*
X1597750D03*
X1597800Y412000D03*
X1601300D03*
X1609250Y426000D03*
X1605750D03*
X1627250Y432000D03*
X1623750D03*
X1627250Y435500D03*
X1623750D03*
X1633250D03*
X1636750D03*
Y432000D03*
X1633250D03*
X1605750Y432500D03*
X1609250D03*
X1605750Y435500D03*
X1609250D03*
Y429000D03*
X1605750D03*
X1614750Y432500D03*
X1618250D03*
X1614750Y429000D03*
X1618250D03*
X1614750Y435500D03*
X1618250D03*
X1614750Y426000D03*
X1618250D03*
X1605449Y422971D03*
X1608949D03*
X1606250Y416000D03*
X1609750D03*
Y412000D03*
X1606250D03*
X1615250Y415500D03*
X1618750D03*
X1620847Y418837D03*
X1617347D03*
X1620847Y421837D03*
X1617347D03*
X1627300Y449800D03*
X1623800D03*
X1605260Y442230D03*
X1608760D03*
X1593600Y491500D03*
X1590100D03*
X1593500Y487300D03*
X1590000D03*
X1615898Y495476D03*
X1619398D03*
X1615898Y492476D03*
X1619398D03*
X1623361Y521918D03*
X1619861D03*
X1623361Y518918D03*
X1619861D03*
X1611057Y465508D03*
X1607557D03*
X1608813Y483559D03*
X1605313D03*
X1608813Y480359D03*
X1605313D03*
X1611057Y468708D03*
X1607557D03*
X1603957Y476708D03*
X1600457D03*
X1603957Y473508D03*
X1600457D03*
X1599104Y580396D03*
X1595604D03*
Y588396D03*
X1599104D03*
Y584396D03*
X1595604D03*
X1599104Y592396D03*
X1595604D03*
X1704900Y63200D03*
X1708400D03*
X1686000Y90000D03*
X1682500D03*
X1689000D03*
X1692500D03*
X1704900Y72968D03*
X1708400D03*
X1684020Y142025D03*
X1687520D03*
X1654819Y212708D03*
X1651319D03*
X1696368Y177380D03*
X1699868D03*
X1693343Y177381D03*
X1689843D03*
X1696400Y174350D03*
X1699900D03*
X1706620Y172616D03*
X1710120D03*
X1693242Y198749D03*
X1696742D03*
X1703242D03*
X1699742D03*
X1659050Y410500D03*
X1662550D03*
X1655550Y413500D03*
X1652050D03*
X1655550Y410500D03*
X1652050D03*
X1659050Y413500D03*
X1662550D03*
X1655250Y445000D03*
X1651750D03*
X1658750D03*
X1662250D03*
X1675650Y494800D03*
X1679150D03*
X1675450Y491800D03*
X1678950D03*
X1675350Y488400D03*
X1678850D03*
X1675750Y511000D03*
X1679250D03*
X1675750Y514000D03*
X1679250D03*
X1675750Y498050D03*
X1679250D03*
X1675750Y501250D03*
X1679250D03*
X1675750Y504550D03*
X1679250D03*
X1695802Y502313D03*
X1699302D03*
X1716163Y3233D03*
X1719663D03*
X1756250Y4500D03*
X1752750D03*
X1745250D03*
X1748750D03*
X1729750Y63500D03*
X1726250D03*
X1723250D03*
X1719750D03*
X1729750Y60500D03*
X1726250D03*
X1723250D03*
X1719750D03*
Y57500D03*
X1723250D03*
X1719750Y66500D03*
X1723250D03*
X1748594Y49606D03*
X1745094D03*
Y55606D03*
X1741594D03*
X1745094Y52606D03*
X1741594D03*
X1762500Y63000D03*
X1759000D03*
X1769000Y83500D03*
X1772500D03*
X1771000Y79800D03*
X1774500D03*
X1719450Y86600D03*
X1722950D03*
X1764529Y111540D03*
X1761029D03*
X1764850Y158650D03*
X1761350D03*
X1739000Y566000D03*
X1735500D03*
X1739000Y563000D03*
X1735500D03*
X1736000Y554000D03*
X1732500D03*
X1745250Y577100D03*
X1748750D03*
X1737814Y581186D03*
X1741314D03*
X1765180Y604490D03*
X1761680D03*
X1833600Y-15700D03*
X1828500Y1000D03*
X1832000D03*
X1808000Y6000D03*
X1811500D03*
X1819000D03*
X1815500D03*
X1795696Y6061D03*
X1792196D03*
X1835500Y800D03*
X1833050Y94550D03*
X1829550D03*
X1833050Y90850D03*
X1829550D03*
X1829500Y87500D03*
X1833000D03*
X1829550Y97850D03*
X1833050D03*
X1807348Y151937D03*
X1803848D03*
X1802750Y120000D03*
X1799250D03*
X1790250D03*
X1793750D03*
X1833023Y101490D03*
X1833047Y104556D03*
X1788250Y126500D03*
X1784750D03*
X1792750Y101800D03*
X1796250D03*
X1833280Y570500D03*
X1776500Y604500D03*
X1780000D03*
X1837100Y-15700D03*
X1889594Y-15042D03*
X1893094D03*
X1889581Y-18335D03*
X1893081D03*
X1839000Y800D03*
X1896581Y-18335D03*
X1893081D03*
X1896594Y-15042D03*
X1893094D03*
X1843500Y81300D03*
X1847000D03*
X1880536Y57002D03*
X1884036D03*
X1880536Y60047D03*
X1884036D03*
X1840250Y81300D03*
X1836750D03*
X1863000Y117500D03*
X1859500D03*
X1863000Y120500D03*
X1859500D03*
X1892370Y140100D03*
X1888870D03*
X1836523Y101490D03*
X1836547Y104556D03*
X1879150Y169100D03*
X1882650D03*
Y166100D03*
X1879150D03*
X1882650Y162600D03*
X1879150D03*
Y159100D03*
X1882650D03*
X1853150Y169600D03*
X1856650D03*
X1880750Y562500D03*
X1884250D03*
X1864750Y545000D03*
X1861250D03*
X1864750Y549500D03*
X1861250D03*
X1836780Y570500D03*
X1896450Y539500D03*
X1891750Y562500D03*
X1888250D03*
X1861961Y557512D03*
X1865461D03*
X1872350Y580350D03*
X1875850D03*
X1957169Y81509D03*
X1931500Y153600D03*
X1935000D03*
X1921800Y137300D03*
X1925300D03*
X1922000Y132500D03*
X1925500D03*
X1906590Y110820D03*
X1903090D03*
X1903790Y115280D03*
X1900290D03*
X1903790Y119280D03*
X1900290D03*
X1946190Y101730D03*
X1949690D03*
X1935450Y196100D03*
X1931950D03*
X1936750Y173600D03*
X1933250D03*
X1930150Y190100D03*
X1933650D03*
Y181100D03*
X1930150D03*
X1933650Y184100D03*
X1930150D03*
X1936750Y165600D03*
X1933250D03*
X1936750Y169600D03*
X1933250D03*
X1936750Y161600D03*
X1933250D03*
X1936750Y157600D03*
X1933250D03*
X1949110Y489180D03*
X1945610D03*
X1929480Y475430D03*
X1925980D03*
X1949050Y492280D03*
X1945550D03*
X1916390Y483910D03*
X1912890D03*
X1916460Y487390D03*
X1912960D03*
X1930250Y566442D03*
X1926750D03*
X1930250Y569442D03*
X1926750D03*
X1917744Y540400D03*
X1921244D03*
X1899950Y539500D03*
X1926750Y572942D03*
X1930250D03*
X1931239Y596040D03*
X1934739D03*
X1931249Y599040D03*
X1934749D03*
X1934699Y605040D03*
X1931199D03*
X1934699Y602040D03*
X1931199D03*
X1929600Y590100D03*
X1926100D03*
X1927015Y611391D03*
X1930515D03*
X1963271Y93138D03*
X1959771D03*
X1960669Y81509D03*
G54D30*
X46986Y-19703D03*
G54D141*
X684400Y228100D03*
X1343072Y40715D03*
X1356960Y9620D03*
X1360800Y368200D03*
X1357200Y556000D03*
X1362482Y618600D03*
G54D204*
X1407473Y553605D03*
X1409048D03*
X1410623D03*
X1412198D03*
X1413773D03*
X1415347D03*
X1416922D03*
X1418497D03*
X1420072D03*
X1421647D03*
X1551113Y615150D03*
X1552688D03*
X1554263D03*
X1555838D03*
X1557413D03*
X1558987D03*
X1560562D03*
X1562137D03*
X1563712D03*
X1565287D03*
G54D123*
X638541Y171945D03*
Y454425D03*
X752641Y159945D03*
Y442425D03*
X1288068Y171945D03*
Y454425D03*
X1402168Y159945D03*
Y442425D03*
X1536123Y23968D03*
X1674921Y528523D03*
Y545059D03*
X1773347Y528523D03*
Y545059D03*
X1872343Y29874D03*
G54D105*
X57684Y647714D03*
Y651654D03*
X206696Y647686D03*
Y651626D03*
X246406Y647814D03*
Y651754D03*
X394280Y647566D03*
Y651506D03*
X433874Y647544D03*
Y651484D03*
X581748Y647296D03*
Y651236D03*
X621422Y647275D03*
Y651215D03*
X897391Y647275D03*
Y651215D03*
X937076Y647264D03*
Y651204D03*
X1210917Y647264D03*
Y651204D03*
X1250574Y647294D03*
Y651234D03*
X1524415Y647294D03*
Y651234D03*
X1570023Y104172D03*
X1611500Y401437D03*
X1731124Y583524D03*
X1729700Y564500D03*
X1956890Y237126D03*
G54D213*
X1495325Y381800D03*
X1501175Y385180D03*
Y391940D03*
Y398700D03*
Y378420D03*
X1507025Y388560D03*
Y395320D03*
Y402080D03*
Y381800D03*
X1512875Y385180D03*
Y391940D03*
Y398700D03*
Y378420D03*
X1489475Y398700D03*
X1518725Y388560D03*
Y381800D03*
Y395320D03*
X1522625Y402080D03*
X1524575Y385180D03*
Y391940D03*
Y398700D03*
Y378420D03*
X1489475D03*
Y385180D03*
Y391940D03*
X1495325Y388560D03*
Y395320D03*
Y402080D03*
X1485575Y398700D03*
Y378420D03*
X1497275Y385180D03*
X1520675Y391940D03*
X1505075Y385180D03*
X1520675Y398700D03*
X1487525Y402080D03*
X1505075Y398700D03*
X1491425Y402080D03*
X1493375Y398700D03*
X1497275D03*
X1514825Y395320D03*
Y381800D03*
X1510925Y395320D03*
Y402080D03*
X1508975Y398700D03*
X1516775Y385180D03*
Y391940D03*
Y398700D03*
X1520675Y385180D03*
X1516775Y378420D03*
X1510925Y381800D03*
X1508975Y378420D03*
Y385180D03*
X1510925Y388560D03*
X1514825D03*
X1508975Y391940D03*
X1514825Y402080D03*
X1518725D03*
X1499225D03*
X1503125D03*
X1522625Y381800D03*
X1526525Y395320D03*
X1522625D03*
Y388560D03*
X1526525D03*
Y402080D03*
Y381800D03*
X1520675Y378420D03*
X1491425Y381800D03*
X1499225Y388560D03*
X1493375Y378420D03*
X1505075Y391940D03*
X1497275Y378420D03*
X1493375Y391940D03*
X1497275D03*
X1499225Y381800D03*
X1505075Y378420D03*
X1503125Y388560D03*
Y395320D03*
Y381800D03*
X1499225Y395320D03*
X1487525Y381800D03*
X1485575Y385180D03*
X1493375D03*
X1487525Y388560D03*
X1485575Y391940D03*
X1491425Y388560D03*
X1487525Y395320D03*
X1491425D03*
X1516775Y405460D03*
X1495325Y429120D03*
Y435880D03*
Y449400D03*
X1499225Y435880D03*
X1517075Y443525D03*
X1499225Y415600D03*
X1503125Y442640D03*
X1499225Y456160D03*
Y462920D03*
X1501175Y405460D03*
Y412220D03*
Y418980D03*
Y425740D03*
Y432500D03*
Y439260D03*
X1523375Y446675D03*
X1501175Y452780D03*
Y459540D03*
X1518725Y456160D03*
X1520225Y449825D03*
X1505073Y412220D03*
Y452780D03*
X1505075Y459540D03*
X1507025Y408840D03*
X1510925Y456160D03*
X1507625Y443525D03*
X1508975Y405460D03*
X1507625Y415175D03*
Y452975D03*
X1508975Y459540D03*
X1510775Y412025D03*
Y415175D03*
Y443525D03*
Y452975D03*
X1512875Y405460D03*
X1513925Y446675D03*
Y415175D03*
Y443525D03*
Y449825D03*
Y452975D03*
X1512875Y459540D03*
X1517075Y418325D03*
Y452975D03*
X1516775Y459540D03*
X1518725Y408840D03*
X1520225Y412025D03*
Y421475D03*
Y440375D03*
Y443525D03*
X1520675Y459540D03*
X1523375Y424625D03*
X1526525Y421475D03*
X1524575Y405460D03*
X1523375Y412025D03*
Y421475D03*
Y427775D03*
Y430925D03*
Y434075D03*
Y437225D03*
Y440375D03*
X1524575Y459540D03*
X1526525Y412025D03*
Y440375D03*
Y449825D03*
Y452975D03*
X1485575Y405460D03*
Y418980D03*
Y432500D03*
Y452780D03*
X1489475Y418980D03*
Y405460D03*
Y432500D03*
Y446020D03*
X1491425Y462920D03*
X1493375Y405460D03*
Y412220D03*
Y418980D03*
Y425740D03*
Y432500D03*
Y439260D03*
X1495325Y442640D03*
Y456160D03*
X1493375Y446020D03*
Y452780D03*
X1495325Y408840D03*
Y415600D03*
Y422360D03*
X1526525Y430925D03*
X1505075Y432500D03*
X1526525Y424625D03*
X1503125Y422360D03*
Y429120D03*
Y435880D03*
X1505075Y418980D03*
Y425740D03*
Y439260D03*
X1507625Y418325D03*
Y421475D03*
Y424625D03*
Y427775D03*
Y430925D03*
Y434075D03*
Y437225D03*
Y440375D03*
X1510775Y418325D03*
Y421475D03*
Y424625D03*
Y427775D03*
Y430925D03*
Y434075D03*
Y437225D03*
Y440375D03*
X1513925Y418325D03*
Y421475D03*
Y424625D03*
Y427775D03*
Y430925D03*
Y434075D03*
Y437225D03*
Y440375D03*
X1503125Y415600D03*
X1517075Y421475D03*
Y424625D03*
Y427775D03*
Y430925D03*
Y434075D03*
Y437225D03*
Y440375D03*
X1520225Y424625D03*
Y427775D03*
Y430925D03*
Y434075D03*
Y437225D03*
X1526525Y427775D03*
Y434075D03*
Y437225D03*
X1517075Y415175D03*
X1520675Y405460D03*
X1526525Y456160D03*
X1514825Y408840D03*
X1517075Y412025D03*
X1526525Y418325D03*
X1520225D03*
X1523375Y415175D03*
X1510775Y446675D03*
Y449825D03*
X1513925Y412025D03*
X1523375Y418325D03*
X1507625Y412025D03*
X1510925Y408840D03*
X1526525Y415175D03*
X1499225Y442640D03*
Y449400D03*
X1501175Y446020D03*
X1503125Y449400D03*
X1505075Y446020D03*
X1507625Y446675D03*
Y449825D03*
X1520225Y415175D03*
X1526525Y408840D03*
X1522625D03*
X1523375Y443525D03*
X1526525D03*
Y446675D03*
X1514825Y456160D03*
X1503125D03*
X1522625D03*
X1520225Y452975D03*
X1517075Y446675D03*
Y449825D03*
X1523375Y452975D03*
Y449825D03*
X1520225Y446675D03*
X1507025Y456160D03*
X1497275Y418980D03*
X1499225Y422360D03*
X1497275Y425740D03*
X1499225Y429120D03*
X1497275Y432500D03*
Y452780D03*
Y446020D03*
Y439260D03*
X1503125Y408840D03*
X1505075Y405460D03*
X1499225Y408840D03*
X1497275Y412220D03*
Y405460D03*
X1526525Y462920D03*
X1507025D03*
X1510925D03*
X1503125D03*
X1514825D03*
X1522625D03*
X1518725D03*
X1487525D03*
X1485575Y459540D03*
X1489475D03*
X1495325Y462920D03*
X1493375Y459540D03*
X1487525Y456160D03*
X1491425Y449400D03*
X1497275Y459540D03*
X1491425Y456160D03*
X1489475Y452780D03*
X1487525Y449400D03*
X1485575Y446020D03*
Y412220D03*
X1491425Y422360D03*
X1485575Y439260D03*
X1487525Y442640D03*
X1485575Y425740D03*
X1487525Y429120D03*
Y415600D03*
Y408840D03*
Y435880D03*
X1489475Y412220D03*
X1487525Y422360D03*
X1489475Y439260D03*
X1491425Y442640D03*
X1489475Y425740D03*
X1491425Y429120D03*
Y415600D03*
Y408840D03*
Y435880D03*
X1497275Y479820D03*
X1501175Y466300D03*
X1499225Y469680D03*
X1501175Y486580D03*
X1503125Y469680D03*
X1507025D03*
X1505075Y486580D03*
X1507025Y476440D03*
X1508975Y473060D03*
Y479820D03*
X1514825Y469680D03*
X1512875Y473060D03*
Y479820D03*
Y486580D03*
X1514825Y483200D03*
X1516775Y466300D03*
Y473060D03*
Y479820D03*
Y486580D03*
X1520675Y466300D03*
Y473060D03*
Y486580D03*
X1524575Y466300D03*
Y473060D03*
Y486580D03*
X1526525Y469680D03*
Y476440D03*
X1485575Y473060D03*
Y479820D03*
Y486580D03*
X1487525Y469680D03*
Y483200D03*
X1489475Y473060D03*
X1510925Y469680D03*
X1512875Y466300D03*
X1518725Y476440D03*
X1508975Y466300D03*
X1505075D03*
X1493375Y486580D03*
X1489475D03*
X1493375Y479820D03*
X1491425Y483200D03*
X1499225Y476440D03*
X1497275Y473060D03*
X1489475Y479820D03*
X1487525Y476440D03*
X1491425D03*
X1495325D03*
X1493375Y473060D03*
X1495325Y469680D03*
X1491425D03*
X1489475Y466300D03*
X1485575D03*
X1493375D03*
X1497275D03*
X1510925Y483200D03*
X1508975Y486580D03*
X1505075Y479820D03*
X1507025Y483200D03*
X1503125Y476440D03*
X1501175Y479820D03*
X1503125Y483200D03*
X1499225D03*
X1505075Y473060D03*
X1501175D03*
X1497275Y486580D03*
X1495325Y483200D03*
X1522625Y469680D03*
X1518725D03*
X1514825Y476440D03*
X1510925D03*
X1520675Y479820D03*
X1522625Y476440D03*
Y483200D03*
X1518725D03*
X1524575Y479820D03*
X1526525Y483200D03*
X1565525Y388560D03*
Y395320D03*
Y381800D03*
X1569425Y402080D03*
X1553825Y381800D03*
X1559675Y385180D03*
Y378420D03*
Y391940D03*
Y398700D03*
X1530425Y388560D03*
Y395320D03*
Y402080D03*
Y381800D03*
X1536275Y378420D03*
Y385180D03*
Y391940D03*
Y398700D03*
X1542125Y381800D03*
Y388560D03*
Y395320D03*
X1547975Y378420D03*
Y385180D03*
Y391940D03*
Y398700D03*
X1553825Y388560D03*
Y395320D03*
Y402080D03*
X1540175Y385180D03*
X1555775D03*
X1544075Y391940D03*
X1540175Y398700D03*
X1542125Y402080D03*
X1546025Y381800D03*
X1544075Y378420D03*
X1546025Y388560D03*
X1549925Y402080D03*
X1555775Y378420D03*
X1546025Y395320D03*
X1540175Y391940D03*
X1551875D03*
Y378420D03*
X1549925Y381800D03*
Y395320D03*
X1551875Y398700D03*
X1540175Y378420D03*
X1544075Y398700D03*
X1549925Y388560D03*
X1546025Y402080D03*
X1551875Y385180D03*
X1544075D03*
X1534325Y402080D03*
X1528475Y398700D03*
X1538225Y395320D03*
X1532375Y398700D03*
X1534325Y395320D03*
X1538225Y402080D03*
Y381800D03*
X1528475Y391940D03*
X1532375D03*
X1538225Y388560D03*
X1534325D03*
X1528475Y385180D03*
X1532375D03*
Y378420D03*
X1534325Y381800D03*
X1528475Y378420D03*
X1557725Y402080D03*
X1567475Y385180D03*
X1569425Y388560D03*
X1555775Y398700D03*
X1561625Y395320D03*
X1567475Y378420D03*
X1569425Y381800D03*
X1565525Y402080D03*
X1569425Y395320D03*
X1557725D03*
X1567475Y391940D03*
X1557725Y381800D03*
X1561625Y402080D03*
X1563575Y391940D03*
X1555775D03*
X1561625Y388560D03*
X1557725D03*
X1567475Y398700D03*
X1563575D03*
X1561625Y381800D03*
X1563575Y385180D03*
Y378420D03*
X1561625Y408840D03*
Y415600D03*
Y422360D03*
Y429120D03*
Y435880D03*
Y442640D03*
Y456160D03*
X1563575Y405460D03*
Y439260D03*
Y432500D03*
X1567475D03*
X1565525Y449400D03*
Y456160D03*
X1567475Y405460D03*
Y459540D03*
X1569425Y456160D03*
Y462920D03*
X1555775Y425740D03*
Y452780D03*
X1557725Y415600D03*
Y435880D03*
Y442640D03*
Y449400D03*
Y462920D03*
X1559675Y412220D03*
Y425740D03*
Y459540D03*
X1529675Y412025D03*
Y421475D03*
Y440375D03*
Y449825D03*
X1532375Y405460D03*
X1532825Y412025D03*
Y421475D03*
Y440375D03*
Y449825D03*
X1532375Y459540D03*
X1534325Y456160D03*
X1536275Y405460D03*
X1535975Y412025D03*
Y421475D03*
Y440375D03*
Y449825D03*
X1539125Y412025D03*
Y421475D03*
Y440375D03*
Y449825D03*
X1538225Y456160D03*
Y462920D03*
X1540175Y405460D03*
X1542275Y412025D03*
Y421475D03*
Y424625D03*
Y427775D03*
Y430925D03*
Y434075D03*
Y437225D03*
Y440375D03*
Y449825D03*
X1542125Y456160D03*
X1544075Y405460D03*
X1546025Y456160D03*
Y462920D03*
X1547975Y405460D03*
Y446020D03*
X1549925Y408840D03*
Y415600D03*
Y422360D03*
Y429120D03*
Y456160D03*
Y462920D03*
X1551875Y418980D03*
Y425740D03*
Y432500D03*
X1553825Y462920D03*
X1555775Y446020D03*
X1553825Y408840D03*
Y415600D03*
Y435880D03*
Y442640D03*
Y456160D03*
X1528475Y405460D03*
Y459540D03*
X1547977Y452780D03*
X1535975Y434075D03*
X1532825Y427775D03*
Y430925D03*
Y434075D03*
Y437225D03*
X1535975Y424625D03*
Y427775D03*
Y430925D03*
X1539125Y424625D03*
Y427775D03*
X1529675Y424625D03*
Y427775D03*
Y430925D03*
Y434075D03*
Y437225D03*
X1532825Y424625D03*
X1539125Y430925D03*
X1529675Y452975D03*
X1530425Y456160D03*
X1532825Y452975D03*
X1539125D03*
X1535975D03*
X1542275D03*
X1530425Y408840D03*
X1545425Y446675D03*
Y449825D03*
X1549925Y449400D03*
X1545425Y452975D03*
X1534325Y408840D03*
X1529675Y415175D03*
X1535975Y437225D03*
X1539125Y434075D03*
Y437225D03*
X1551875Y452780D03*
X1553825Y449400D03*
X1542275Y415175D03*
X1532825Y418325D03*
X1529675D03*
X1535975D03*
X1542275D03*
X1539125D03*
X1538225Y408840D03*
X1547977Y412220D03*
X1546025Y408840D03*
X1545425Y412025D03*
X1539125Y415175D03*
X1551875Y446020D03*
X1545425Y443525D03*
X1551875Y439260D03*
Y412220D03*
X1542125Y408840D03*
X1545425Y421475D03*
Y424625D03*
Y427775D03*
Y430925D03*
Y434075D03*
X1547975Y425740D03*
Y432500D03*
X1545425Y415175D03*
Y418325D03*
Y437225D03*
Y440375D03*
X1547975Y439260D03*
X1549925Y435880D03*
X1529675Y446675D03*
X1532825Y443525D03*
Y446675D03*
X1535975Y443525D03*
Y446675D03*
X1539125Y443525D03*
Y446675D03*
X1542275Y443525D03*
X1529675D03*
X1542275Y446675D03*
X1535975Y415175D03*
X1532825D03*
X1555775Y412220D03*
X1557725Y408840D03*
X1551875Y405460D03*
X1563575Y452780D03*
X1559675D03*
X1547975Y459540D03*
X1536275D03*
X1540175D03*
X1551875D03*
X1555775D03*
X1544075D03*
X1542125Y462920D03*
X1567475Y452780D03*
X1557725Y456160D03*
X1569425Y435880D03*
X1565525D03*
Y442640D03*
X1567475Y446020D03*
X1569425Y449400D03*
X1559675Y446020D03*
X1563575D03*
X1567475Y439260D03*
X1561625Y449400D03*
X1569425Y442640D03*
X1559675Y405460D03*
X1555775D03*
X1567475Y425740D03*
X1563575D03*
X1555775Y439260D03*
X1559675D03*
X1567475Y412220D03*
X1563575D03*
Y418980D03*
X1567475D03*
X1565525Y422360D03*
X1569425D03*
Y429120D03*
X1565525D03*
X1569425Y408840D03*
X1565525D03*
X1569425Y415600D03*
X1565525D03*
X1557725Y429120D03*
X1553825D03*
X1555775Y432500D03*
X1559675D03*
Y418980D03*
X1555775D03*
X1553825Y422360D03*
X1557725D03*
X1549925Y442640D03*
X1547975Y418980D03*
X1530425Y462920D03*
X1534325D03*
X1565525D03*
X1561625D03*
X1563575Y459540D03*
Y479820D03*
X1565525Y469680D03*
X1567475Y473060D03*
Y486580D03*
X1569425Y469680D03*
X1553825D03*
Y476440D03*
Y483200D03*
X1555775Y473060D03*
Y479820D03*
X1530425Y469680D03*
X1532375Y486580D03*
X1534325Y469680D03*
Y483200D03*
X1536275Y473060D03*
X1538225Y476440D03*
X1540175Y473060D03*
X1542125Y469680D03*
Y476440D03*
X1544075Y466300D03*
Y479820D03*
X1546025Y469680D03*
X1547975Y473060D03*
Y486580D03*
X1551875Y466300D03*
Y473060D03*
Y479820D03*
Y486580D03*
X1528475Y473060D03*
X1540175Y466300D03*
X1538225Y469680D03*
X1532375Y466300D03*
X1528475D03*
X1536275D03*
X1563575Y486580D03*
X1561625Y483200D03*
X1569425D03*
X1565525D03*
X1567475Y479820D03*
X1569425Y476440D03*
X1561625D03*
X1557725D03*
X1547975Y466300D03*
X1549925Y469680D03*
X1544075Y486580D03*
X1542125Y483200D03*
X1549925D03*
X1546025D03*
Y476440D03*
X1544075Y473060D03*
X1549925Y476440D03*
X1547975Y479820D03*
X1559675D03*
X1557725Y483200D03*
X1559675Y486580D03*
X1555775D03*
X1530425Y476440D03*
X1532375Y473060D03*
X1528475Y479820D03*
X1532375D03*
X1530425Y483200D03*
X1528475Y486580D03*
X1536275Y479820D03*
X1534325Y476440D03*
X1540175Y486580D03*
X1536275D03*
X1538225Y483200D03*
X1540175Y479820D03*
X1565525Y476440D03*
X1563575Y473060D03*
X1559675D03*
X1561625Y469680D03*
X1555775Y466300D03*
X1557725Y469680D03*
X1567475Y466300D03*
X1559675D03*
X1563575D03*
G54D114*
X311021Y35957D03*
X334446Y65814D03*
X334447Y35957D03*
X347833D03*
X344486Y529022D03*
Y536957D03*
X354525Y529022D03*
X334447Y536957D03*
X324407Y529014D03*
X314368Y566814D03*
X321061D03*
X344486Y566822D03*
X364565Y28014D03*
X414762Y28021D03*
X404723Y35957D03*
X401377Y536957D03*
X414763D03*
Y566822D03*
Y593657D03*
X438189Y28022D03*
X444882Y35957D03*
X434842Y73757D03*
X444882Y536957D03*
X434842D03*
X421456Y529022D03*
X444880Y566822D03*
X438187Y593659D03*
X963976Y566814D03*
X960629Y574757D03*
Y536957D03*
X970669Y529014D03*
X984054D03*
X997441Y574757D03*
X987401D03*
X994094Y529022D03*
X1004133D03*
X1087797Y566822D03*
X1094490Y574757D03*
X1054331Y529022D03*
X1094490Y536957D03*
X1496004Y374823D03*
X1499941D03*
X1503878D03*
X1507815D03*
X1511752D03*
X1515689D03*
X1519626D03*
Y371555D03*
X1523563Y374823D03*
X1527500D03*
X1476732Y387224D03*
Y399035D03*
X1480000Y387224D03*
Y395098D03*
Y399035D03*
X1481634Y385256D03*
Y389193D03*
Y393130D03*
Y401004D03*
X1481437Y376988D03*
X1481634Y381319D03*
X1484622Y375979D03*
X1488130Y374823D03*
X1492067D03*
X1494035Y369921D03*
Y373189D03*
X1490098D03*
X1486161D03*
X1492067Y371555D03*
X1482673Y374030D03*
X1488130Y371555D03*
X1490098Y369921D03*
X1483071Y378957D03*
X1480000Y383287D03*
X1478366Y381319D03*
Y385256D03*
X1476732Y383287D03*
X1481634Y397067D03*
X1478366D03*
X1480000Y379350D03*
X1525531Y373189D03*
X1523563Y371555D03*
X1521594Y369921D03*
X1525531D03*
X1527500Y371555D03*
X1521594Y373189D03*
X1499941Y371555D03*
X1509783Y369921D03*
X1497972D03*
Y373189D03*
X1505846Y369921D03*
X1517657Y373189D03*
Y369921D03*
X1505846Y373189D03*
X1507815Y371555D03*
X1503878D03*
X1515689D03*
X1501909Y369921D03*
X1513720Y373189D03*
X1511752Y371555D03*
X1501909Y373189D03*
X1513720Y369921D03*
X1509783Y373189D03*
X1496004Y371555D03*
X1478366Y389193D03*
X1476732Y395098D03*
X1480000Y391161D03*
X1478366Y393130D03*
X1476732Y391161D03*
X1480000Y402972D03*
X1478366Y401004D03*
X1476732Y402972D03*
Y410846D03*
Y414783D03*
Y450217D03*
X1478366Y404941D03*
Y420689D03*
Y428563D03*
Y432500D03*
Y440374D03*
X1480000Y410846D03*
Y414783D03*
Y450217D03*
X1481634Y404941D03*
Y408878D03*
Y412815D03*
Y416752D03*
Y420689D03*
Y424626D03*
Y428563D03*
Y432500D03*
Y436437D03*
Y440374D03*
Y444311D03*
Y448248D03*
Y452185D03*
Y456122D03*
Y460059D03*
Y463996D03*
X1478366D03*
X1476732Y462028D03*
X1480000D03*
X1478366Y460059D03*
X1476732Y458091D03*
X1480000D03*
X1478366Y456122D03*
X1476732Y454154D03*
X1480000D03*
X1478366Y452185D03*
X1476732Y446280D03*
Y442343D03*
X1478366Y448248D03*
X1480000Y446280D03*
X1478366Y444311D03*
X1480000Y442343D03*
Y430531D03*
X1476732D03*
X1478366Y412815D03*
X1476732Y422657D03*
Y426594D03*
X1478366Y416752D03*
X1480000Y406909D03*
Y422657D03*
Y426594D03*
X1478366Y408878D03*
X1476732Y406909D03*
X1480000Y438406D03*
X1476732D03*
X1480000Y418720D03*
X1476732D03*
X1480000Y434469D03*
X1476732D03*
X1478366Y424626D03*
Y436437D03*
X1527500Y490177D03*
Y493445D03*
X1496004Y490177D03*
X1499941D03*
X1503878D03*
X1507815D03*
X1511752D03*
Y493445D03*
X1515689Y490177D03*
X1519626D03*
X1523563D03*
X1525531Y491811D03*
Y495079D03*
X1507815Y493445D03*
X1478366Y483681D03*
X1481634Y471870D03*
Y483681D03*
Y467933D03*
Y475807D03*
Y479744D03*
X1488130Y490177D03*
Y493445D03*
X1490098Y491811D03*
Y495079D03*
X1492067Y490177D03*
X1484094Y484469D03*
X1482673Y490970D03*
X1476732Y469902D03*
X1480000D03*
X1478366Y467933D03*
X1476732Y465965D03*
X1480000D03*
X1476732Y481713D03*
X1480000D03*
X1478366Y479744D03*
X1476732Y477776D03*
X1480000D03*
X1478366Y475807D03*
X1476732Y473839D03*
X1480000D03*
X1478366Y471870D03*
X1509783Y495079D03*
Y491811D03*
X1486161D03*
X1484622Y489021D03*
X1517657Y495079D03*
Y491811D03*
X1519626Y493445D03*
X1521594Y495079D03*
Y491811D03*
X1523563Y493445D03*
X1492067D03*
X1494035Y495079D03*
Y491811D03*
X1496004Y493445D03*
X1497972Y495079D03*
Y491811D03*
X1499941Y493445D03*
X1501909Y495079D03*
Y491811D03*
X1503878Y493445D03*
X1505846Y495079D03*
Y491811D03*
X1513720Y495079D03*
Y491811D03*
X1515689Y493445D03*
X1481634Y487618D03*
X1480000Y485650D03*
X1576634Y397067D03*
X1562933Y374823D03*
X1566870D03*
X1571732Y379350D03*
X1570378Y375979D03*
X1573366Y389193D03*
Y385256D03*
Y393130D03*
Y397067D03*
Y401004D03*
Y381319D03*
X1576634Y393130D03*
X1558996Y374823D03*
Y371555D03*
X1531437Y374823D03*
X1533406Y369921D03*
Y373189D03*
X1535374Y374823D03*
X1539311D03*
X1543248D03*
X1547185D03*
X1551122D03*
X1555059D03*
X1529469Y369921D03*
X1531437Y371555D03*
X1529469Y373189D03*
X1566870Y371555D03*
X1564902Y373189D03*
Y369921D03*
X1573366Y377382D03*
X1562933Y371555D03*
X1560965Y369921D03*
X1568839Y373189D03*
X1575000Y391161D03*
X1578268Y387224D03*
X1575000D03*
X1576634Y389193D03*
X1560965Y373189D03*
X1578268Y391161D03*
Y383287D03*
X1575000D03*
X1576634Y381319D03*
Y385256D03*
X1572327Y374030D03*
X1575000Y379350D03*
X1578268Y402972D03*
X1576634Y401004D03*
X1575000Y402972D03*
X1553091Y369921D03*
X1535374Y371555D03*
X1541280Y369921D03*
X1543248Y371555D03*
X1537343Y369921D03*
X1539311Y371555D03*
X1557028Y373189D03*
Y369921D03*
X1545217D03*
X1555059Y371555D03*
X1541280Y373189D03*
X1551122Y371555D03*
X1549154Y373189D03*
X1553091D03*
X1547185Y371555D03*
X1549154Y369921D03*
X1545217Y373189D03*
X1537343D03*
X1575000Y399035D03*
X1578268D03*
Y395098D03*
X1575000D03*
X1576634Y412815D03*
Y460059D03*
X1578268Y438406D03*
Y454154D03*
X1575000D03*
X1573366Y404941D03*
Y408878D03*
Y412815D03*
Y416752D03*
Y420689D03*
Y424626D03*
Y428563D03*
Y432500D03*
Y436437D03*
Y440374D03*
Y444311D03*
Y448248D03*
Y452185D03*
Y456122D03*
Y460059D03*
Y463996D03*
X1575000Y438406D03*
X1576634Y404941D03*
X1575000Y406909D03*
X1576634Y408878D03*
X1578268Y406909D03*
X1575000Y410846D03*
X1578268D03*
Y442343D03*
X1576634Y440374D03*
Y448248D03*
X1575000Y446280D03*
X1576634Y452185D03*
X1575000Y442343D03*
X1576634Y444311D03*
X1578268Y446280D03*
Y450217D03*
X1575000D03*
X1578268Y418720D03*
X1576634Y424626D03*
X1575000Y430531D03*
X1576634Y428563D03*
Y420689D03*
X1575000Y418720D03*
X1578268Y414783D03*
Y426594D03*
X1575000Y414783D03*
X1576634Y436437D03*
X1578268Y430531D03*
Y422657D03*
X1576634Y432500D03*
X1578268Y434469D03*
X1575000D03*
Y426594D03*
Y422657D03*
X1576634Y416752D03*
X1575000Y462028D03*
X1576634Y463996D03*
X1578268Y462028D03*
X1575000Y458091D03*
X1578268D03*
X1576634Y456122D03*
X1562933Y490177D03*
Y493445D03*
X1564902Y491811D03*
Y495079D03*
X1571732Y485650D03*
X1573366Y467933D03*
Y471870D03*
Y475807D03*
Y479744D03*
X1555059Y490177D03*
X1558996D03*
X1531437D03*
X1535374D03*
Y493445D03*
X1539311Y490177D03*
X1543248D03*
X1547185D03*
Y493445D03*
X1549154Y491811D03*
Y495079D03*
X1551122Y490177D03*
X1568839Y491811D03*
X1572327Y490970D03*
X1537343Y491811D03*
Y495079D03*
X1541280Y491811D03*
Y495079D03*
X1543248Y493445D03*
X1545217Y491811D03*
Y495079D03*
X1539311Y493445D03*
X1533406Y495079D03*
Y491811D03*
X1529469Y495079D03*
Y491811D03*
X1531437Y493445D03*
X1551122D03*
X1553091Y491811D03*
Y495079D03*
X1555059Y493445D03*
X1557028Y491811D03*
Y495079D03*
X1558996Y493445D03*
X1560965Y491811D03*
Y495079D03*
X1570378Y489021D03*
X1566870Y493445D03*
X1575000Y465965D03*
Y481713D03*
X1576634Y467933D03*
Y479744D03*
X1575000Y469902D03*
Y477776D03*
X1576634Y471870D03*
Y475807D03*
X1573366Y487618D03*
X1575000Y485650D03*
X1573366Y483681D03*
X1575000Y473839D03*
X1578268Y465965D03*
Y481713D03*
Y469902D03*
Y477776D03*
X1576634Y483681D03*
X1578268Y473839D03*
X1566870Y490177D03*
G54D160*
X1255730Y314160D03*
G54D115*
X306092Y100800D03*
X309981Y104689D03*
X955700Y100800D03*
X959589Y104689D03*
G54D322*
X1965132Y477599D03*
X1973450D03*
X1965132Y506339D03*
X1973450D03*
G54D133*
X665396Y12500D03*
Y14469D03*
Y16437D03*
Y18406D03*
Y20374D03*
X676700D03*
Y18406D03*
Y16437D03*
Y14469D03*
Y12500D03*
X665795Y576493D03*
Y578462D03*
Y580430D03*
Y582399D03*
Y584367D03*
X677099D03*
Y582399D03*
Y580430D03*
Y578462D03*
Y576493D03*
X1782548Y89000D03*
Y90968D03*
Y92937D03*
X1793852Y90968D03*
Y89000D03*
Y87031D03*
Y92937D03*
X1782548Y85063D03*
X1793852D03*
X1782548Y87031D03*
X1812848Y155563D03*
X1824152D03*
X1812848Y159500D03*
Y161468D03*
Y163437D03*
X1824152Y161468D03*
Y159500D03*
Y157531D03*
Y163437D03*
X1812848Y157531D03*
G54D313*
X1953940Y219803D03*
Y221771D03*
Y229645D03*
Y227677D03*
G54D151*
X1245946Y265866D03*
G54D223*
X1473888Y615130D03*
X1475660D03*
X1477431D03*
X1479203D03*
X1480975D03*
X1482746D03*
X1484518D03*
X1486290D03*
X1488061D03*
X1489833D03*
X1509426Y616398D03*
X1511198D03*
X1512969D03*
X1514741D03*
X1516513D03*
X1518284D03*
X1520056D03*
X1521828D03*
X1523599D03*
X1525371D03*
G54D304*
X1955426Y104548D03*
Y100612D03*
Y102580D03*
Y98644D03*
X1963526Y100612D03*
Y104548D03*
Y102580D03*
Y98644D03*
G54D22*
X-15831Y547265D03*
X-15361Y583807D03*
X4400Y71700D03*
X-1100D03*
X-10331Y547265D03*
X-9861Y583807D03*
X47070Y607000D03*
X69652Y4240D03*
X75152D03*
X108500Y259500D03*
Y227500D03*
X107966Y290332D03*
X108200Y322500D03*
X52570Y607000D03*
X168200Y207870D03*
X114000Y259500D03*
Y227500D03*
X113466Y290332D03*
X113700Y322500D03*
X116250Y356500D03*
X110750D03*
X116120Y388180D03*
X110620D03*
X173700Y207870D03*
X179150Y202100D03*
X173650D03*
X386048Y275141D03*
X391548D03*
X386056Y270241D03*
X391556D03*
X599000Y13000D03*
Y51000D03*
X598950Y89550D03*
X598900Y513200D03*
X598800Y551200D03*
Y589000D03*
X616500Y13000D03*
X611000D03*
X604500D03*
X660112Y39650D03*
X654612D03*
X616900Y51000D03*
X611400D03*
X616150Y89550D03*
X610650D03*
X604500Y51000D03*
X604450Y89550D03*
X643300Y295200D03*
X637800D03*
X615900Y513200D03*
X610400D03*
X604400D03*
X618000Y589000D03*
X612500D03*
X618500Y551200D03*
X613000D03*
X604300D03*
Y589000D03*
X720596Y84030D03*
X726096D03*
X675972Y40376D03*
X681472D03*
X671261Y40403D03*
X665761D03*
X718000Y211000D03*
X723500D03*
X677600Y526000D03*
X683100D03*
X672895Y526398D03*
X667395D03*
X689680Y582490D03*
X684180D03*
X670700Y569400D03*
X665200D03*
X763500Y228000D03*
X758000D03*
X764500Y260105D03*
X759000D03*
X763950Y323658D03*
X758450D03*
X761700Y292000D03*
X756200D03*
X763875Y355850D03*
X758375D03*
X765400Y388700D03*
X759900D03*
X818500Y207870D03*
X824000D03*
X1035656Y270241D03*
X1041156D03*
X1035656Y275141D03*
X1041156D03*
X1248608Y13000D03*
X1254108D03*
X1266108D03*
X1260608D03*
X1248608Y51000D03*
X1254108D03*
X1266508D03*
X1261008D03*
X1248608Y89528D03*
X1254108D03*
X1266108D03*
X1260608D03*
X1249000Y513200D03*
X1254500D03*
X1265500D03*
X1260000D03*
X1248608Y552000D03*
X1254108D03*
X1266508D03*
X1261008D03*
X1248608Y590000D03*
X1254108D03*
X1266108D03*
X1260608D03*
X1319200Y99450D03*
X1313700D03*
X1337134Y99469D03*
X1331634D03*
X1341700Y409200D03*
X1336200D03*
X1341700Y404300D03*
X1336200D03*
X1330342Y513603D03*
X1324842D03*
X1382247Y-9885D03*
X1387747D03*
X1385946Y379926D03*
X1391446D03*
X1385116Y568907D03*
X1390616D03*
X1385250Y599500D03*
X1390750D03*
X1444047Y402785D03*
X1449547D03*
X1507300Y552900D03*
X1501800D03*
X1507300Y558050D03*
X1501800D03*
X1515829Y556974D03*
X1521329D03*
X1515970Y551760D03*
X1521470D03*
X1485000Y622600D03*
X1490500D03*
X1521094Y622646D03*
X1526594D03*
X1559545Y274225D03*
X1554045D03*
X1585170Y571204D03*
X1558950Y578800D03*
X1553450D03*
X1606500Y371948D03*
X1601000D03*
X1606500Y367248D03*
X1601000D03*
X1600750Y460500D03*
X1595250D03*
X1600750Y465500D03*
X1595250D03*
X1624000Y502200D03*
X1618500D03*
X1590670Y571204D03*
X1596004Y601196D03*
X1590504D03*
X1765753Y115662D03*
X1760253D03*
X1784500Y105700D03*
X1779000D03*
X1791750Y97800D03*
X1797250D03*
X1836630Y138000D03*
X1797348Y166937D03*
X1802848D03*
X1842130Y138000D03*
X1887100Y546100D03*
X1881600D03*
G54D106*
X167124Y3233D03*
X163777D03*
X160431D03*
X157084D03*
X153738D03*
X150392D03*
X147045D03*
X143699D03*
X140352D03*
X137006D03*
X133659D03*
X130313D03*
X126966D03*
X123620D03*
X120273D03*
X116927D03*
X167124Y-14877D03*
X163777D03*
X160431D03*
X157084D03*
X153738D03*
X150392D03*
X147045D03*
X143699D03*
X140352D03*
X137006D03*
X133659D03*
X130313D03*
X126966D03*
X123620D03*
X120273D03*
X116927D03*
X167124Y22923D03*
X163777D03*
X160431D03*
X157084D03*
X153738D03*
X150392D03*
X147045D03*
X143699D03*
X140352D03*
X137006D03*
X133659D03*
X130313D03*
X126966D03*
X123620D03*
X120273D03*
X116927D03*
X167124Y78833D03*
X163777D03*
X160431D03*
X157084D03*
X153738D03*
X150392D03*
X147045D03*
X143699D03*
X140352D03*
X137006D03*
X133659D03*
X130313D03*
X126966D03*
X123620D03*
X120273D03*
X116927D03*
X167124Y60723D03*
X163777D03*
X160431D03*
X157084D03*
X153738D03*
X150392D03*
X147045D03*
X143699D03*
X140352D03*
X137006D03*
X133659D03*
X130313D03*
X126966D03*
X123620D03*
X120273D03*
X116927D03*
X167124Y41033D03*
X163777D03*
X160431D03*
X157084D03*
X153738D03*
X150392D03*
X147045D03*
X143699D03*
X140352D03*
X137006D03*
X133659D03*
X130313D03*
X126966D03*
X123620D03*
X120273D03*
X116927D03*
X167124Y523900D03*
X163777D03*
X160431D03*
X157084D03*
X153738D03*
X150392D03*
X147045D03*
X143699D03*
X140352D03*
X137006D03*
X133659D03*
X130313D03*
X126966D03*
X123620D03*
X120273D03*
X116927D03*
X167124Y542010D03*
X163777D03*
X160431D03*
X157084D03*
X153738D03*
X150392D03*
X147045D03*
X143699D03*
X140352D03*
X137006D03*
X133659D03*
X130313D03*
X126966D03*
X123620D03*
X120273D03*
X116927D03*
Y561700D03*
Y579810D03*
X120273Y561700D03*
X126966D03*
X133659D03*
X143699D03*
X150392D03*
X157084D03*
X163777D03*
X123620Y579810D03*
X130313D03*
X137006D03*
X147045D03*
X153738D03*
X160431D03*
X167124D03*
X137006Y561700D03*
X140352D03*
X143699Y579810D03*
X140352D03*
X120273D03*
X167124Y561700D03*
X150392Y579810D03*
X147045Y561700D03*
X126966Y579810D03*
X123620Y561700D03*
X157084Y579810D03*
X153738Y561700D03*
X133659Y579810D03*
X163777D03*
X160431Y561700D03*
X130313D03*
X167124Y617610D03*
X163777D03*
X160431D03*
X157084D03*
X153738D03*
X150392D03*
X147045D03*
X143699D03*
X140352D03*
X137006D03*
X133659D03*
X130313D03*
X126966D03*
X123620D03*
X120273D03*
X116927D03*
X167124Y599500D03*
X163777D03*
X160431D03*
X157084D03*
X153738D03*
X150392D03*
X147045D03*
X143699D03*
X140352D03*
X137006D03*
X133659D03*
X130313D03*
X126966D03*
X123620D03*
X120273D03*
X116927D03*
X230707Y3233D03*
X227360D03*
X224014D03*
X220667D03*
X217321D03*
X213974D03*
X210628D03*
X207281D03*
X203935D03*
X200588D03*
X197242D03*
X193896D03*
X190549D03*
X187203D03*
X183856D03*
X180510D03*
X177163D03*
X173817D03*
X170470D03*
X230707Y-14877D03*
X227360D03*
X224014D03*
X220667D03*
X217321D03*
X213974D03*
X210628D03*
X207281D03*
X203935D03*
X200588D03*
X197242D03*
X193896D03*
X190549D03*
X187203D03*
X183856D03*
X180510D03*
X177163D03*
X173817D03*
X170470D03*
X230707Y22923D03*
X227360D03*
X224014D03*
X220667D03*
X217321D03*
X213974D03*
X210628D03*
X207281D03*
X203935D03*
X200588D03*
X197242D03*
X193896D03*
X190549D03*
X187203D03*
X183856D03*
X180510D03*
X177163D03*
X173817D03*
X170470D03*
X230707Y78833D03*
X227360D03*
X224014D03*
X220667D03*
X217321D03*
X213974D03*
X210628D03*
X207281D03*
X203935D03*
X200588D03*
X197242D03*
X193896D03*
X190549D03*
X187203D03*
X183856D03*
X180510D03*
X177163D03*
X173817D03*
X170470D03*
X230707Y60723D03*
X227360D03*
X224014D03*
X220667D03*
X217321D03*
X213974D03*
X210628D03*
X207281D03*
X203935D03*
X200588D03*
X197242D03*
X193896D03*
X190549D03*
X187203D03*
X183856D03*
X180510D03*
X177163D03*
X173817D03*
X170470D03*
X230707Y41033D03*
X227360D03*
X224014D03*
X220667D03*
X217321D03*
X213974D03*
X210628D03*
X207281D03*
X203935D03*
X200588D03*
X197242D03*
X193896D03*
X190549D03*
X187203D03*
X183856D03*
X180510D03*
X177163D03*
X173817D03*
X170470D03*
X230707Y523900D03*
X227360D03*
X224014D03*
X220667D03*
X217321D03*
X213974D03*
X210628D03*
X207281D03*
X203935D03*
X200588D03*
X197242D03*
X193896D03*
X190549D03*
X187203D03*
X183856D03*
X180510D03*
X177163D03*
X173817D03*
X170470D03*
X230707Y542010D03*
X227360D03*
X224014D03*
X220667D03*
X217321D03*
X213974D03*
X210628D03*
X207281D03*
X203935D03*
X200588D03*
X197242D03*
X193896D03*
X190549D03*
X187203D03*
X183856D03*
X180510D03*
X177163D03*
X173817D03*
X170470D03*
Y561700D03*
X180510D03*
X187203D03*
X193896D03*
X200588D03*
X207281D03*
X217321D03*
X224014D03*
X230707D03*
X173817Y579810D03*
X183856D03*
X190549D03*
X197242D03*
X203935D03*
X210628D03*
X220667D03*
X227360D03*
X217321D03*
X213974D03*
X180510D03*
X177163D03*
X210628Y561700D03*
X213974D03*
X173817D03*
X177163D03*
X170470Y579810D03*
X224014D03*
X220667Y561700D03*
X200588Y579810D03*
X197242Y561700D03*
X230707Y579810D03*
X227360Y561700D03*
X207281Y579810D03*
X203935Y561700D03*
X187203Y579810D03*
X183856Y561700D03*
X193896Y579810D03*
X190549Y561700D03*
X230707Y617610D03*
X227360D03*
X224014D03*
X220667D03*
X217321D03*
X213974D03*
X210628D03*
X207281D03*
X203935D03*
X200588D03*
X197242D03*
X193896D03*
X190549D03*
X187203D03*
X183856D03*
X180510D03*
X177163D03*
X173817D03*
X170470D03*
X230707Y599500D03*
X227360D03*
X224014D03*
X220667D03*
X217321D03*
X213974D03*
X210628D03*
X207281D03*
X203935D03*
X200588D03*
X197242D03*
X193896D03*
X190549D03*
X187203D03*
X183856D03*
X180510D03*
X177163D03*
X173817D03*
X170470D03*
X290943Y3233D03*
X287596D03*
X284250D03*
X280903D03*
X277557D03*
X274210D03*
X270864D03*
X267518D03*
X264171D03*
X260825D03*
X257478D03*
X254132D03*
X250785D03*
X247439D03*
X244092D03*
X240746D03*
X237399D03*
X234053D03*
X290943Y-14877D03*
X287596D03*
X284250D03*
X280903D03*
X277557D03*
X274210D03*
X270864D03*
X267518D03*
X264171D03*
X260825D03*
X257478D03*
X254132D03*
X250785D03*
X247439D03*
X244092D03*
X240746D03*
X237399D03*
X234053D03*
X290943Y22923D03*
X287596D03*
X284250D03*
X280903D03*
X277557D03*
X274210D03*
X270864D03*
X267518D03*
X264171D03*
X260825D03*
X257478D03*
X254132D03*
X250785D03*
X247439D03*
X244092D03*
X240746D03*
X237399D03*
X234053D03*
X290943Y78833D03*
X287596D03*
X284250D03*
X280903D03*
X277557D03*
X274210D03*
X270864D03*
X267518D03*
X264171D03*
X260825D03*
X257478D03*
X254132D03*
X250785D03*
X247439D03*
X244092D03*
X240746D03*
X237399D03*
X234053D03*
X290943Y60723D03*
X287596D03*
X284250D03*
X280903D03*
X277557D03*
X274210D03*
X270864D03*
X267518D03*
X264171D03*
X260825D03*
X257478D03*
X254132D03*
X250785D03*
X247439D03*
X244092D03*
X240746D03*
X237399D03*
X234053D03*
X290943Y41033D03*
X287596D03*
X284250D03*
X280903D03*
X277557D03*
X274210D03*
X270864D03*
X267518D03*
X264171D03*
X260825D03*
X257478D03*
X254132D03*
X250785D03*
X247439D03*
X244092D03*
X240746D03*
X237399D03*
X234053D03*
X290943Y523900D03*
X287596D03*
X284250D03*
X280903D03*
X277557D03*
X274210D03*
X270864D03*
X267518D03*
X264171D03*
X260825D03*
X257478D03*
X254132D03*
X250785D03*
X247439D03*
X244092D03*
X240746D03*
X237399D03*
X234053D03*
X290943Y542010D03*
X287596D03*
X284250D03*
X280903D03*
X277557D03*
X274210D03*
X270864D03*
X267518D03*
X264171D03*
X260825D03*
X257478D03*
X254132D03*
X250785D03*
X247439D03*
X244092D03*
X240746D03*
X237399D03*
X234053D03*
X237399Y561700D03*
X244092D03*
X254132D03*
X260825D03*
X267518D03*
X274210D03*
X280903D03*
X290943D03*
X234053Y579810D03*
X240746D03*
X247439D03*
X257478D03*
X264171D03*
X270864D03*
X277557D03*
X284250D03*
X290943D03*
X287596D03*
X254132D03*
X250785D03*
X284250Y561700D03*
X287596D03*
X247439D03*
X250785D03*
X260825Y579810D03*
X257478Y561700D03*
X237399Y579810D03*
X234053Y561700D03*
X267518Y579810D03*
X264171Y561700D03*
X244092Y579810D03*
X240746Y561700D03*
X274210Y579810D03*
X270864Y561700D03*
X280903Y579810D03*
X277557Y561700D03*
X290943Y617610D03*
X287596D03*
X284250D03*
X280903D03*
X277557D03*
X274210D03*
X270864D03*
X267518D03*
X264171D03*
X260825D03*
X257478D03*
X254132D03*
X250785D03*
X247439D03*
X244092D03*
X240746D03*
X237399D03*
X234053D03*
X290943Y599500D03*
X287596D03*
X284250D03*
X280903D03*
X277557D03*
X274210D03*
X270864D03*
X267518D03*
X264171D03*
X260825D03*
X257478D03*
X254132D03*
X250785D03*
X247439D03*
X244092D03*
X240746D03*
X237399D03*
X234053D03*
X354525Y3233D03*
X351179D03*
X347833D03*
X344486D03*
X341140D03*
X337793D03*
X334447D03*
X331100D03*
X327754D03*
X324407D03*
X321061D03*
X317714D03*
X314368D03*
X311021D03*
X307675D03*
X304329D03*
X300982D03*
X297636D03*
X294289D03*
X354525Y-14877D03*
X351179D03*
X347833D03*
X344486D03*
X341140D03*
X337793D03*
X334447D03*
X331100D03*
X327754D03*
X324407D03*
X321061D03*
X317714D03*
X314368D03*
X311021D03*
X307675D03*
X304329D03*
X300982D03*
X297636D03*
X294289D03*
X354525Y22923D03*
X351179D03*
X347833D03*
X344486D03*
X341140D03*
X337793D03*
X334447D03*
X331100D03*
X327754D03*
X324407D03*
X321061D03*
X317714D03*
X314368D03*
X311021D03*
X307675D03*
X304329D03*
X300982D03*
X297636D03*
X294289D03*
X354525Y78833D03*
X351179D03*
X347833D03*
X344486D03*
X341140D03*
X337793D03*
X334447D03*
X331100D03*
X327754D03*
X324407D03*
X321061D03*
X317714D03*
X314368D03*
X311021D03*
X307675D03*
X304329D03*
X300982D03*
X297636D03*
X294289D03*
X354525Y60723D03*
X351179D03*
X347833D03*
X344486D03*
X341140D03*
X337793D03*
X334447D03*
X331100D03*
X327754D03*
X324407D03*
X321061D03*
X317714D03*
X314368D03*
X311021D03*
X307675D03*
X304329D03*
X300982D03*
X297636D03*
X294289D03*
X354525Y41033D03*
X351179D03*
X347833D03*
X344486D03*
X341140D03*
X337793D03*
X334447D03*
X331100D03*
X327754D03*
X324407D03*
X321061D03*
X317714D03*
X314368D03*
X311021D03*
X307675D03*
X304329D03*
X300982D03*
X297636D03*
X294289D03*
X354525Y523900D03*
X351179D03*
X347833D03*
X344486D03*
X341140D03*
X337793D03*
X334447D03*
X331100D03*
X327754D03*
X324407D03*
X321061D03*
X317714D03*
X314368D03*
X311021D03*
X307675D03*
X304329D03*
X300982D03*
X297636D03*
X294289D03*
X354525Y542010D03*
X351179D03*
X347833D03*
X344486D03*
X341140D03*
X337793D03*
X334447D03*
X331100D03*
X327754D03*
X324407D03*
X321061D03*
X317714D03*
X314368D03*
X311021D03*
X307675D03*
X304329D03*
X300982D03*
X297636D03*
X294289D03*
X341140Y579810D03*
X351179D03*
X311021Y561700D03*
X317714D03*
X327754D03*
X337793D03*
X347833D03*
X314368Y579810D03*
X321061D03*
X331100D03*
X297636Y561700D03*
X304329D03*
X294289Y579810D03*
X300982D03*
X307675D03*
X317714D03*
X307675Y561700D03*
X311021Y579810D03*
X314368Y561700D03*
X297636Y579810D03*
X294289Y561700D03*
X304329Y579810D03*
X300982Y561700D03*
X324407Y579810D03*
Y561700D03*
X327754Y579810D03*
X321061Y561700D03*
X334447D03*
X341140D03*
X337793Y579810D03*
X344486Y561700D03*
Y579810D03*
X347833D03*
X351179Y561700D03*
X354525Y579810D03*
X331100Y561700D03*
X334447Y579810D03*
X354525Y561700D03*
Y617610D03*
X351179D03*
X347833D03*
X344486D03*
X341140D03*
X337793D03*
X334447D03*
X331100D03*
X327754D03*
X324407D03*
X321061D03*
X317714D03*
X314368D03*
X311021D03*
X307675D03*
X304329D03*
X300982D03*
X297636D03*
X294289D03*
X354525Y599500D03*
X351179D03*
X347833D03*
X344486D03*
X341140D03*
X337793D03*
X334447D03*
X331100D03*
X327754D03*
X324407D03*
X321061D03*
X317714D03*
X314368D03*
X311021D03*
X307675D03*
X304329D03*
X300982D03*
X297636D03*
X294289D03*
X414762Y3233D03*
X411415D03*
X408069D03*
X404722D03*
X401376D03*
X398029D03*
X394683D03*
X371258D03*
X367911D03*
X364565D03*
X361218D03*
X357872D03*
X414762Y-14877D03*
X411415D03*
X408069D03*
X404722D03*
X401376D03*
X398029D03*
X394683D03*
X371258D03*
X367911D03*
X364565D03*
X361218D03*
X357872D03*
X414762Y22923D03*
X411415D03*
X408069D03*
X404722D03*
X401376D03*
X398029D03*
X394683D03*
X371258D03*
X367911D03*
X364565D03*
X361218D03*
X357872D03*
X414762Y78833D03*
X411415D03*
X408069D03*
X404722D03*
X401376D03*
X398029D03*
X394683D03*
X371258D03*
X367911D03*
X364565D03*
X361218D03*
X357872D03*
X414762Y60723D03*
X411415D03*
X408069D03*
X404722D03*
X401376D03*
X398029D03*
X394683D03*
X371258D03*
X367911D03*
X364565D03*
X361218D03*
X357872D03*
X414762Y41033D03*
X411415D03*
X408069D03*
X404722D03*
X401376D03*
X398029D03*
X394683D03*
X371258D03*
X367911D03*
X364565D03*
X361218D03*
X357872D03*
X414762Y523900D03*
X411415D03*
X408069D03*
X404722D03*
X401376D03*
X398029D03*
X394683D03*
X371258D03*
X367911D03*
X364565D03*
X361218D03*
X357872D03*
X414762Y542010D03*
X411415D03*
X408069D03*
X404722D03*
X401376D03*
X398029D03*
X394683D03*
X371258D03*
X367911D03*
X364565D03*
X361218D03*
X357872D03*
X371258Y561700D03*
Y579810D03*
X357872D03*
X367911D03*
X398029D03*
X408069D03*
X357872Y561700D03*
X367911D03*
X401376D03*
X411415D03*
X414762D03*
X411415Y579810D03*
X394683D03*
Y561700D03*
X361218Y579810D03*
X364565D03*
X361218Y561700D03*
X364565D03*
X401376Y579810D03*
X404722Y561700D03*
X408069D03*
X414762Y579810D03*
X404722D03*
X398029Y561700D03*
X414762Y617610D03*
X411415D03*
X408069D03*
X404722D03*
X401376D03*
X398029D03*
X394683D03*
X371258D03*
X367911D03*
X364565D03*
X361218D03*
X357872D03*
X414762Y599500D03*
X411415D03*
X408069D03*
X404722D03*
X401376D03*
X398029D03*
X394683D03*
X371258D03*
X367911D03*
X364565D03*
X361218D03*
X357872D03*
X478344Y3233D03*
X474998D03*
X471651D03*
X468305D03*
X464958D03*
X461612D03*
X458266D03*
X454919D03*
X451573D03*
X448226D03*
X444880D03*
X441533D03*
X438187D03*
X434840D03*
X431494D03*
X428147D03*
X424801D03*
X421455D03*
X418108D03*
X478344Y-14877D03*
X474998D03*
X471651D03*
X468305D03*
X464958D03*
X461612D03*
X458266D03*
X454919D03*
X451573D03*
X448226D03*
X444880D03*
X441533D03*
X438187D03*
X434840D03*
X431494D03*
X428147D03*
X424801D03*
X421455D03*
X418108D03*
X478344Y22923D03*
X474998D03*
X471651D03*
X468305D03*
X464958D03*
X461612D03*
X458266D03*
X454919D03*
X451573D03*
X448226D03*
X444880D03*
X441533D03*
X438187D03*
X434840D03*
X431494D03*
X428147D03*
X424801D03*
X421455D03*
X418108D03*
X478344Y78833D03*
X474998D03*
X471651D03*
X468305D03*
X464958D03*
X461612D03*
X458266D03*
X454919D03*
X451573D03*
X448226D03*
X444880D03*
X441533D03*
X438187D03*
X434840D03*
X431494D03*
X428147D03*
X424801D03*
X421455D03*
X418108D03*
X478344Y60723D03*
X474998D03*
X471651D03*
X468305D03*
X464958D03*
X461612D03*
X458266D03*
X454919D03*
X451573D03*
X448226D03*
X444880D03*
X441533D03*
X438187D03*
X434840D03*
X431494D03*
X428147D03*
X424801D03*
X421455D03*
X418108D03*
X478344Y41033D03*
X474998D03*
X471651D03*
X468305D03*
X464958D03*
X461612D03*
X458266D03*
X454919D03*
X451573D03*
X448226D03*
X444880D03*
X441533D03*
X438187D03*
X434840D03*
X431494D03*
X428147D03*
X424801D03*
X421455D03*
X418108D03*
X478344Y523900D03*
X474998D03*
X471651D03*
X468305D03*
X464958D03*
X461612D03*
X458266D03*
X454919D03*
X451573D03*
X448226D03*
X444880D03*
X441533D03*
X438187D03*
X434840D03*
X431494D03*
X428147D03*
X424801D03*
X421455D03*
X418108D03*
X478344Y542010D03*
X474998D03*
X471651D03*
X468305D03*
X464958D03*
X461612D03*
X458266D03*
X454919D03*
X451573D03*
X448226D03*
X444880D03*
X441533D03*
X438187D03*
X434840D03*
X431494D03*
X428147D03*
X424801D03*
X421455D03*
X418108D03*
Y579810D03*
X424801D03*
X431494D03*
X418108Y561700D03*
X428147D03*
X434840D03*
X441533D03*
Y579810D03*
X448226Y561700D03*
X454919D03*
X461612D03*
X471651D03*
X478344D03*
X451573Y579810D03*
X458266D03*
X464958D03*
X474998D03*
X471651D03*
X468305D03*
X464958Y561700D03*
X468305D03*
X421455Y579810D03*
X448226D03*
X444880D03*
Y561700D03*
X431494D03*
X438187D03*
X424801D03*
X478344Y579810D03*
X474998Y561700D03*
X454919Y579810D03*
X451573Y561700D03*
X461612Y579810D03*
X458266Y561700D03*
X438187Y579810D03*
X434840D03*
X421455Y561700D03*
X428147Y579810D03*
X478344Y617610D03*
X474998D03*
X471651D03*
X468305D03*
X464958D03*
X461612D03*
X458266D03*
X454919D03*
X451573D03*
X448226D03*
X444880D03*
X441533D03*
X438187D03*
X434840D03*
X431494D03*
X428147D03*
X424801D03*
X421455D03*
X418108D03*
X478344Y599500D03*
X474998D03*
X471651D03*
X468305D03*
X464958D03*
X461612D03*
X458266D03*
X454919D03*
X451573D03*
X448226D03*
X444880D03*
X441533D03*
X438187D03*
X434840D03*
X431494D03*
X428147D03*
X424801D03*
X421455D03*
X418108D03*
X538581Y3233D03*
X535234D03*
X531888D03*
X528541D03*
X525195D03*
X521848D03*
X518502D03*
X515155D03*
X511809D03*
X508462D03*
X505116D03*
X501770D03*
X498423D03*
X495077D03*
X491730D03*
X488384D03*
X485037D03*
X481691D03*
X538581Y-14877D03*
X535234D03*
X531888D03*
X528541D03*
X525195D03*
X521848D03*
X518502D03*
X515155D03*
X511809D03*
X508462D03*
X505116D03*
X501770D03*
X498423D03*
X495077D03*
X491730D03*
X488384D03*
X485037D03*
X481691D03*
X538581Y22923D03*
X535234D03*
X531888D03*
X528541D03*
X525195D03*
X521848D03*
X518502D03*
X515155D03*
X511809D03*
X508462D03*
X505116D03*
X501770D03*
X498423D03*
X495077D03*
X491730D03*
X488384D03*
X485037D03*
X481691D03*
X538581Y78833D03*
X535234D03*
X531888D03*
X528541D03*
X525195D03*
X521848D03*
X518502D03*
X515155D03*
X511809D03*
X508462D03*
X505116D03*
X501770D03*
X498423D03*
X495077D03*
X491730D03*
X488384D03*
X485037D03*
X481691D03*
X538581Y60723D03*
X535234D03*
X531888D03*
X528541D03*
X525195D03*
X521848D03*
X518502D03*
X515155D03*
X511809D03*
X508462D03*
X505116D03*
X501770D03*
X498423D03*
X495077D03*
X491730D03*
X488384D03*
X485037D03*
X481691D03*
X538581Y41033D03*
X535234D03*
X531888D03*
X528541D03*
X525195D03*
X521848D03*
X518502D03*
X515155D03*
X511809D03*
X508462D03*
X505116D03*
X501770D03*
X498423D03*
X495077D03*
X491730D03*
X488384D03*
X485037D03*
X481691D03*
X538581Y523900D03*
X535234D03*
X531888D03*
X528541D03*
X525195D03*
X521848D03*
X518502D03*
X515155D03*
X511809D03*
X508462D03*
X505116D03*
X501770D03*
X498423D03*
X495077D03*
X491730D03*
X488384D03*
X485037D03*
X481691D03*
X538581Y542010D03*
X535234D03*
X531888D03*
X528541D03*
X525195D03*
X521848D03*
X518502D03*
X515155D03*
X511809D03*
X508462D03*
X505116D03*
X501770D03*
X498423D03*
X495077D03*
X491730D03*
X488384D03*
X485037D03*
X481691D03*
X531888Y579810D03*
X538581D03*
X485037Y561700D03*
X491730D03*
X498423D03*
X508462D03*
X515155D03*
X521848D03*
X528541D03*
X535234D03*
X481691Y579810D03*
X488384D03*
X495077D03*
X501770D03*
X511809D03*
X518502D03*
X525195D03*
X508462D03*
X505116D03*
X538581Y561700D03*
X501770D03*
X505116D03*
X528541Y579810D03*
X525195Y561700D03*
X535234Y579810D03*
X531888Y561700D03*
X515155Y579810D03*
X511809Y561700D03*
X491730Y579810D03*
X488384Y561700D03*
X521848Y579810D03*
X518502Y561700D03*
X498423Y579810D03*
X495077Y561700D03*
X485037Y579810D03*
X481691Y561700D03*
X538581Y617610D03*
X535234D03*
X531888D03*
X528541D03*
X525195D03*
X521848D03*
X518502D03*
X515155D03*
X511809D03*
X508462D03*
X505116D03*
X501770D03*
X498423D03*
X495077D03*
X491730D03*
X488384D03*
X485037D03*
X481691D03*
X538581Y599500D03*
X535234D03*
X531888D03*
X528541D03*
X525195D03*
X521848D03*
X518502D03*
X515155D03*
X511809D03*
X508462D03*
X505116D03*
X501770D03*
X498423D03*
X495077D03*
X491730D03*
X488384D03*
X485037D03*
X481691D03*
X602163Y3233D03*
X598817D03*
X595470D03*
X592124D03*
X588777D03*
X585431D03*
X582084D03*
X578738D03*
X575392D03*
X572045D03*
X568699D03*
X565352D03*
X562006D03*
X558659D03*
X555313D03*
X551966D03*
X548620D03*
X545273D03*
X541927D03*
X602163Y-14877D03*
X598817D03*
X595470D03*
X592124D03*
X588777D03*
X585431D03*
X582084D03*
X578738D03*
X575392D03*
X572045D03*
X568699D03*
X565352D03*
X562006D03*
X558659D03*
X555313D03*
X551966D03*
X548620D03*
X545273D03*
X541927D03*
X602163Y22923D03*
X598817D03*
X595470D03*
X592124D03*
X588777D03*
X585431D03*
X582084D03*
X578738D03*
X575392D03*
X572045D03*
X568699D03*
X565352D03*
X562006D03*
X558659D03*
X555313D03*
X551966D03*
X548620D03*
X545273D03*
X541927D03*
X602163Y78833D03*
X598817D03*
X595470D03*
X592124D03*
X588777D03*
X585431D03*
X582084D03*
X578738D03*
X575392D03*
X572045D03*
X568699D03*
X565352D03*
X562006D03*
X558659D03*
X555313D03*
X551966D03*
X548620D03*
X545273D03*
X541927D03*
X602163Y60723D03*
X598817D03*
X595470D03*
X592124D03*
X588777D03*
X585431D03*
X582084D03*
X578738D03*
X575392D03*
X572045D03*
X568699D03*
X565352D03*
X562006D03*
X558659D03*
X555313D03*
X551966D03*
X548620D03*
X545273D03*
X541927D03*
X602163Y41033D03*
X598817D03*
X595470D03*
X592124D03*
X588777D03*
X585431D03*
X582084D03*
X578738D03*
X575392D03*
X572045D03*
X568699D03*
X565352D03*
X562006D03*
X558659D03*
X555313D03*
X551966D03*
X548620D03*
X545273D03*
X541927D03*
X602163Y523900D03*
X598817D03*
X595470D03*
X592124D03*
X588777D03*
X585431D03*
X582084D03*
X578738D03*
X575392D03*
X572045D03*
X568699D03*
X565352D03*
X562006D03*
X558659D03*
X555313D03*
X551966D03*
X548620D03*
X545273D03*
X541927D03*
X602163Y542010D03*
X598817D03*
X595470D03*
X592124D03*
X588777D03*
X585431D03*
X582084D03*
X578738D03*
X575392D03*
X572045D03*
X568699D03*
X565352D03*
X562006D03*
X558659D03*
X555313D03*
X551966D03*
X548620D03*
X545273D03*
X541927D03*
X548620Y579810D03*
X555313D03*
X562006D03*
X545273Y561700D03*
X551966D03*
X558659D03*
X565352D03*
X572045D03*
X568699Y579810D03*
X582084Y561700D03*
X588777D03*
X595470D03*
X575392Y579810D03*
X585431D03*
X592124D03*
X598817D03*
X582084D03*
X578738D03*
X545273D03*
X541927D03*
X575392Y561700D03*
X578738D03*
X541927D03*
X602163Y579810D03*
Y561700D03*
X598817D03*
X588777Y579810D03*
X585431Y561700D03*
X565352Y579810D03*
X562006Y561700D03*
X595470Y579810D03*
X592124Y561700D03*
X572045Y579810D03*
X568699Y561700D03*
X551966Y579810D03*
X548620Y561700D03*
X558659Y579810D03*
X555313Y561700D03*
X602163Y617610D03*
X598817D03*
X595470D03*
X592124D03*
X588777D03*
X585431D03*
X582084D03*
X578738D03*
X575392D03*
X572045D03*
X568699D03*
X565352D03*
X562006D03*
X558659D03*
X555313D03*
X551966D03*
X548620D03*
X545273D03*
X541927D03*
X602163Y599500D03*
X598817D03*
X595470D03*
X592124D03*
X588777D03*
X585431D03*
X582084D03*
X578738D03*
X575392D03*
X572045D03*
X568699D03*
X565352D03*
X562006D03*
X558659D03*
X555313D03*
X551966D03*
X548620D03*
X545273D03*
X541927D03*
X615549Y3233D03*
X612203D03*
X608856D03*
X605510D03*
X615549Y-14877D03*
X612203D03*
X608856D03*
X605510D03*
X615549Y22923D03*
X612203D03*
X608856D03*
X605510D03*
X615549Y78833D03*
X612203D03*
X608856D03*
X605510D03*
X615549Y60723D03*
X612203D03*
X608856D03*
X605510D03*
X615549Y41033D03*
X612203D03*
X608856D03*
X605510D03*
X615549Y523900D03*
X612203D03*
X608856D03*
X605510D03*
X615549Y542010D03*
X612203D03*
X608856D03*
X605510D03*
X608856Y561700D03*
X612203D03*
X615549Y579810D03*
X608856D03*
X612203D03*
X605510D03*
Y561700D03*
X615549D03*
Y617610D03*
X612203D03*
X608856D03*
X605510D03*
X615549Y599500D03*
X612203D03*
X608856D03*
X605510D03*
X786616Y3233D03*
X783269D03*
X779923D03*
X776576D03*
X773230D03*
X769883D03*
X766537D03*
X786616Y-14877D03*
X783269D03*
X779923D03*
X776576D03*
X773230D03*
X769883D03*
X766537D03*
X786616Y22923D03*
X783269D03*
X779923D03*
X776576D03*
X773230D03*
X769883D03*
X766537D03*
X786616Y78833D03*
X783269D03*
X779923D03*
X776576D03*
X773230D03*
X769883D03*
X766537D03*
X786616Y60723D03*
X783269D03*
X779923D03*
X776576D03*
X773230D03*
X769883D03*
X766537D03*
X786616Y41033D03*
X783269D03*
X779923D03*
X776576D03*
X773230D03*
X769883D03*
X766537D03*
X786616Y523900D03*
X783269D03*
X779923D03*
X776576D03*
X773230D03*
X769883D03*
X766537D03*
X786616Y579810D03*
X783269D03*
X779923D03*
X776576D03*
X773230D03*
X769883D03*
X766537D03*
X786616Y561700D03*
X783269D03*
X779923D03*
X776576D03*
X773230D03*
X769883D03*
X766537D03*
X786616Y542010D03*
X783269D03*
X779923D03*
X776576D03*
X773230D03*
X769883D03*
X766537D03*
X786616Y617610D03*
X783269D03*
X779923D03*
X776576D03*
X773230D03*
X769883D03*
X766537D03*
X786616Y599500D03*
X783269D03*
X779923D03*
X776576D03*
X773230D03*
X769883D03*
X766537D03*
X846852Y3233D03*
X843506D03*
X840159D03*
X836813D03*
X833466D03*
X830120D03*
X826773D03*
X823427D03*
X820080D03*
X816734D03*
X813387D03*
X810041D03*
X806694D03*
X803348D03*
X800002D03*
X796655D03*
X793309D03*
X789962D03*
X846852Y-14877D03*
X843506D03*
X840159D03*
X836813D03*
X833466D03*
X830120D03*
X826773D03*
X823427D03*
X820080D03*
X816734D03*
X813387D03*
X810041D03*
X806694D03*
X803348D03*
X800002D03*
X796655D03*
X793309D03*
X789962D03*
X846852Y22923D03*
X843506D03*
X840159D03*
X836813D03*
X833466D03*
X830120D03*
X826773D03*
X823427D03*
X820080D03*
X816734D03*
X813387D03*
X810041D03*
X806694D03*
X803348D03*
X800002D03*
X796655D03*
X793309D03*
X789962D03*
X846852Y78833D03*
X843506D03*
X840159D03*
X836813D03*
X833466D03*
X830120D03*
X826773D03*
X823427D03*
X820080D03*
X816734D03*
X813387D03*
X810041D03*
X806694D03*
X803348D03*
X800002D03*
X796655D03*
X793309D03*
X789962D03*
X846852Y60723D03*
X843506D03*
X840159D03*
X836813D03*
X833466D03*
X830120D03*
X826773D03*
X823427D03*
X820080D03*
X816734D03*
X813387D03*
X810041D03*
X806694D03*
X803348D03*
X800002D03*
X796655D03*
X793309D03*
X789962D03*
X846852Y41033D03*
X843506D03*
X840159D03*
X836813D03*
X833466D03*
X830120D03*
X826773D03*
X823427D03*
X820080D03*
X816734D03*
X813387D03*
X810041D03*
X806694D03*
X803348D03*
X800002D03*
X796655D03*
X793309D03*
X789962D03*
X846852Y523900D03*
X843506D03*
X840159D03*
X836813D03*
X833466D03*
X830120D03*
X826773D03*
X823427D03*
X820080D03*
X816734D03*
X813387D03*
X810041D03*
X806694D03*
X803348D03*
X800002D03*
X796655D03*
X793309D03*
X789962D03*
X846852Y579810D03*
X843506D03*
X840159D03*
X836813D03*
X833466D03*
X830120D03*
X826773D03*
X823427D03*
X820080D03*
X816734D03*
X813387D03*
X810041D03*
X806694D03*
X803348D03*
X800002D03*
X796655D03*
X793309D03*
X789962D03*
X846852Y561700D03*
X843506D03*
X840159D03*
X836813D03*
X833466D03*
X830120D03*
X826773D03*
X823427D03*
X820080D03*
X816734D03*
X813387D03*
X810041D03*
X806694D03*
X803348D03*
X800002D03*
X796655D03*
X793309D03*
X789962D03*
X846852Y542010D03*
X843506D03*
X840159D03*
X836813D03*
X833466D03*
X830120D03*
X826773D03*
X823427D03*
X820080D03*
X816734D03*
X813387D03*
X810041D03*
X806694D03*
X803348D03*
X800002D03*
X796655D03*
X793309D03*
X789962D03*
X846852Y617610D03*
X843506D03*
X840159D03*
X836813D03*
X833466D03*
X830120D03*
X826773D03*
X823427D03*
X820080D03*
X816734D03*
X813387D03*
X810041D03*
X806694D03*
X803348D03*
X800002D03*
X796655D03*
X793309D03*
X789962D03*
X846852Y599500D03*
X843506D03*
X840159D03*
X836813D03*
X833466D03*
X830120D03*
X826773D03*
X823427D03*
X820080D03*
X816734D03*
X813387D03*
X810041D03*
X806694D03*
X803348D03*
X800002D03*
X796655D03*
X793309D03*
X789962D03*
X910435Y3233D03*
X907088D03*
X903742D03*
X900395D03*
X897049D03*
X893702D03*
X890356D03*
X887009D03*
X883663D03*
X880317D03*
X876970D03*
X873624D03*
X870277D03*
X866931D03*
X863584D03*
X860238D03*
X856891D03*
X853545D03*
X850198D03*
X910435Y-14877D03*
X907088D03*
X903742D03*
X900395D03*
X897049D03*
X893702D03*
X890356D03*
X887009D03*
X883663D03*
X880317D03*
X876970D03*
X873624D03*
X870277D03*
X866931D03*
X863584D03*
X860238D03*
X856891D03*
X853545D03*
X850198D03*
X910435Y22923D03*
X907088D03*
X903742D03*
X900395D03*
X897049D03*
X893702D03*
X890356D03*
X887009D03*
X883663D03*
X880317D03*
X876970D03*
X873624D03*
X870277D03*
X866931D03*
X863584D03*
X860238D03*
X856891D03*
X853545D03*
X850198D03*
X910435Y78833D03*
X907088D03*
X903742D03*
X900395D03*
X897049D03*
X893702D03*
X890356D03*
X887009D03*
X883663D03*
X880317D03*
X876970D03*
X873624D03*
X870277D03*
X866931D03*
X863584D03*
X860238D03*
X856891D03*
X853545D03*
X850198D03*
X910435Y60723D03*
X907088D03*
X903742D03*
X900395D03*
X897049D03*
X893702D03*
X890356D03*
X887009D03*
X883663D03*
X880317D03*
X876970D03*
X873624D03*
X870277D03*
X866931D03*
X863584D03*
X860238D03*
X856891D03*
X853545D03*
X850198D03*
X910435Y41033D03*
X907088D03*
X903742D03*
X900395D03*
X897049D03*
X893702D03*
X890356D03*
X887009D03*
X883663D03*
X880317D03*
X876970D03*
X873624D03*
X870277D03*
X866931D03*
X863584D03*
X860238D03*
X856891D03*
X853545D03*
X850198D03*
X910435Y523900D03*
X907088D03*
X903742D03*
X900395D03*
X897049D03*
X893702D03*
X890356D03*
X887009D03*
X883663D03*
X880317D03*
X876970D03*
X873624D03*
X870277D03*
X866931D03*
X863584D03*
X860238D03*
X856891D03*
X853545D03*
X850198D03*
X910435Y579810D03*
X907088D03*
X903742D03*
X900395D03*
X897049D03*
X893702D03*
X890356D03*
X887009D03*
X883663D03*
X880317D03*
X876970D03*
X873624D03*
X870277D03*
X866931D03*
X863584D03*
X860238D03*
X856891D03*
X853545D03*
X850198D03*
X910435Y561700D03*
X907088D03*
X903742D03*
X900395D03*
X897049D03*
X893702D03*
X890356D03*
X887009D03*
X883663D03*
X880317D03*
X876970D03*
X873624D03*
X870277D03*
X866931D03*
X863584D03*
X860238D03*
X856891D03*
X853545D03*
X850198D03*
X910435Y542010D03*
X907088D03*
X903742D03*
X900395D03*
X897049D03*
X893702D03*
X890356D03*
X887009D03*
X883663D03*
X880317D03*
X876970D03*
X873624D03*
X870277D03*
X866931D03*
X863584D03*
X860238D03*
X856891D03*
X853545D03*
X850198D03*
X910435Y617610D03*
X907088D03*
X903742D03*
X900395D03*
X897049D03*
X893702D03*
X890356D03*
X887009D03*
X883663D03*
X880317D03*
X876970D03*
X873624D03*
X870277D03*
X866931D03*
X863584D03*
X860238D03*
X856891D03*
X853545D03*
X850198D03*
X910435Y599500D03*
X907088D03*
X903742D03*
X900395D03*
X897049D03*
X893702D03*
X890356D03*
X887009D03*
X883663D03*
X880317D03*
X876970D03*
X873624D03*
X870277D03*
X866931D03*
X863584D03*
X860238D03*
X856891D03*
X853545D03*
X850198D03*
X970671Y3233D03*
X967324D03*
X963978D03*
X960631D03*
X957285D03*
X953939D03*
X950592D03*
X947246D03*
X943899D03*
X940553D03*
X937206D03*
X933860D03*
X930513D03*
X927167D03*
X923820D03*
X920474D03*
X917128D03*
X913781D03*
X970671Y-14877D03*
X967324D03*
X963978D03*
X960631D03*
X957285D03*
X953939D03*
X950592D03*
X947246D03*
X943899D03*
X940553D03*
X937206D03*
X933860D03*
X930513D03*
X927167D03*
X923820D03*
X920474D03*
X917128D03*
X913781D03*
X970671Y22923D03*
X967324D03*
X963978D03*
X960631D03*
X957285D03*
X953939D03*
X950592D03*
X947246D03*
X943899D03*
X940553D03*
X937206D03*
X933860D03*
X930513D03*
X927167D03*
X923820D03*
X920474D03*
X917128D03*
X913781D03*
X970671Y78833D03*
X967324D03*
X963978D03*
X960631D03*
X957285D03*
X953939D03*
X950592D03*
X947246D03*
X943899D03*
X940553D03*
X937206D03*
X933860D03*
X930513D03*
X927167D03*
X923820D03*
X920474D03*
X917128D03*
X913781D03*
X970671Y60723D03*
X967324D03*
X963978D03*
X960631D03*
X957285D03*
X953939D03*
X950592D03*
X947246D03*
X943899D03*
X940553D03*
X937206D03*
X933860D03*
X930513D03*
X927167D03*
X923820D03*
X920474D03*
X917128D03*
X913781D03*
X970671Y41033D03*
X967324D03*
X963978D03*
X960631D03*
X957285D03*
X953939D03*
X950592D03*
X947246D03*
X943899D03*
X940553D03*
X937206D03*
X933860D03*
X930513D03*
X927167D03*
X923820D03*
X920474D03*
X917128D03*
X913781D03*
X970671Y523900D03*
X967324D03*
X963978D03*
X960631D03*
X957285D03*
X953939D03*
X950592D03*
X947246D03*
X943899D03*
X940553D03*
X937206D03*
X933860D03*
X930513D03*
X927167D03*
X923820D03*
X920474D03*
X917128D03*
X913781D03*
X970671Y579810D03*
X967324D03*
X963978D03*
X960631D03*
X957285D03*
X953939D03*
X950592D03*
X947246D03*
X943899D03*
X940553D03*
X937206D03*
X933860D03*
X930513D03*
X927167D03*
X923820D03*
X920474D03*
X917128D03*
X913781D03*
X970671Y561700D03*
X967324D03*
X963978D03*
X960631D03*
X957285D03*
X953939D03*
X950592D03*
X947246D03*
X943899D03*
X940553D03*
X937206D03*
X933860D03*
X930513D03*
X927167D03*
X923820D03*
X920474D03*
X917128D03*
X913781D03*
X970671Y542010D03*
X967324D03*
X963978D03*
X960631D03*
X957285D03*
X953939D03*
X950592D03*
X947246D03*
X943899D03*
X940553D03*
X937206D03*
X933860D03*
X930513D03*
X927167D03*
X923820D03*
X920474D03*
X917128D03*
X913781D03*
X970671Y617610D03*
X967324D03*
X963978D03*
X960631D03*
X957285D03*
X953939D03*
X950592D03*
X947246D03*
X943899D03*
X940553D03*
X937206D03*
X933860D03*
X930513D03*
X927167D03*
X923820D03*
X920474D03*
X917128D03*
X913781D03*
X970671Y599500D03*
X967324D03*
X963978D03*
X960631D03*
X957285D03*
X953939D03*
X950592D03*
X947246D03*
X943899D03*
X940553D03*
X937206D03*
X933860D03*
X930513D03*
X927167D03*
X923820D03*
X920474D03*
X917128D03*
X913781D03*
X1020868Y3233D03*
X1017521D03*
X1014175D03*
X1010828D03*
X1007482D03*
X1004135D03*
X1000789D03*
X997443D03*
X994096D03*
X990750D03*
X987403D03*
X984057D03*
X980710D03*
X977364D03*
X974017D03*
X1020868Y-14877D03*
X1017521D03*
X1014175D03*
X1010828D03*
X1007482D03*
X1004135D03*
X1000789D03*
X997443D03*
X994096D03*
X990750D03*
X987403D03*
X984057D03*
X980710D03*
X977364D03*
X974017D03*
X1020868Y22923D03*
X1017521D03*
X1014175D03*
X1010828D03*
X1007482D03*
X1004135D03*
X1000789D03*
X997443D03*
X994096D03*
X990750D03*
X987403D03*
X984057D03*
X980710D03*
X977364D03*
X974017D03*
X1020868Y78833D03*
X1017521D03*
X1014175D03*
X1010828D03*
X1007482D03*
X1004135D03*
X1000789D03*
X997443D03*
X994096D03*
X990750D03*
X987403D03*
X984057D03*
X980710D03*
X977364D03*
X974017D03*
X1020868Y60723D03*
X1017521D03*
X1014175D03*
X1010828D03*
X1007482D03*
X1004135D03*
X1000789D03*
X997443D03*
X994096D03*
X990750D03*
X987403D03*
X984057D03*
X980710D03*
X977364D03*
X974017D03*
X1020868Y41033D03*
X1017521D03*
X1014175D03*
X1010828D03*
X1007482D03*
X1004135D03*
X1000789D03*
X997443D03*
X994096D03*
X990750D03*
X987403D03*
X984057D03*
X980710D03*
X977364D03*
X974017D03*
X1020868Y523900D03*
X1017521D03*
X1014175D03*
X1010828D03*
X1007482D03*
X1004135D03*
X1000789D03*
X997443D03*
X994096D03*
X990750D03*
X987403D03*
X984057D03*
X980710D03*
X977364D03*
X974017D03*
X1020868Y579810D03*
X1017521D03*
X1014175D03*
X1010828D03*
X1007482D03*
X1004135D03*
X1000789D03*
X997443D03*
X994096D03*
X990750D03*
X987403D03*
X984057D03*
X980710D03*
X977364D03*
X974017D03*
X1020868Y561700D03*
X1017521D03*
X1014175D03*
X1010828D03*
X1007482D03*
X1004135D03*
X1000789D03*
X997443D03*
X994096D03*
X990750D03*
X987403D03*
X984057D03*
X980710D03*
X977364D03*
X974017D03*
X1020868Y542010D03*
X1017521D03*
X1014175D03*
X1010828D03*
X1007482D03*
X1004135D03*
X1000789D03*
X997443D03*
X994096D03*
X990750D03*
X987403D03*
X984057D03*
X980710D03*
X977364D03*
X974017D03*
X1020868Y617610D03*
X1017521D03*
X1014175D03*
X1010828D03*
X1007482D03*
X1004135D03*
X1000789D03*
X997443D03*
X994096D03*
X990750D03*
X987403D03*
X984057D03*
X980710D03*
X977364D03*
X974017D03*
X1020868Y599500D03*
X1017521D03*
X1014175D03*
X1010828D03*
X1007482D03*
X1004135D03*
X1000789D03*
X997443D03*
X994096D03*
X990750D03*
X987403D03*
X984057D03*
X980710D03*
X977364D03*
X974017D03*
X1094490Y3233D03*
X1091143D03*
X1087797D03*
X1084450D03*
X1081104D03*
X1077757D03*
X1074411D03*
X1071065D03*
X1067718D03*
X1064372D03*
X1061025D03*
X1057679D03*
X1054332D03*
X1050986D03*
X1047639D03*
X1044293D03*
X1094490Y-14877D03*
X1091143D03*
X1087797D03*
X1084450D03*
X1081104D03*
X1077757D03*
X1074411D03*
X1071065D03*
X1067718D03*
X1064372D03*
X1061025D03*
X1057679D03*
X1054332D03*
X1050986D03*
X1047639D03*
X1044293D03*
X1094490Y22923D03*
X1091143D03*
X1087797D03*
X1084450D03*
X1081104D03*
X1077757D03*
X1074411D03*
X1071065D03*
X1067718D03*
X1064372D03*
X1061025D03*
X1057679D03*
X1054332D03*
X1050986D03*
X1047639D03*
X1044293D03*
X1094490Y78833D03*
X1091143D03*
X1087797D03*
X1084450D03*
X1081104D03*
X1077757D03*
X1074411D03*
X1071065D03*
X1067718D03*
X1064372D03*
X1061025D03*
X1057679D03*
X1054332D03*
X1050986D03*
X1047639D03*
X1044293D03*
X1094490Y60723D03*
X1091143D03*
X1087797D03*
X1084450D03*
X1081104D03*
X1077757D03*
X1074411D03*
X1071065D03*
X1067718D03*
X1064372D03*
X1061025D03*
X1057679D03*
X1054332D03*
X1050986D03*
X1047639D03*
X1044293D03*
X1094490Y41033D03*
X1091143D03*
X1087797D03*
X1084450D03*
X1081104D03*
X1077757D03*
X1074411D03*
X1071065D03*
X1067718D03*
X1064372D03*
X1061025D03*
X1057679D03*
X1054332D03*
X1050986D03*
X1047639D03*
X1044293D03*
X1094490Y523900D03*
X1091143D03*
X1087797D03*
X1084450D03*
X1081104D03*
X1077757D03*
X1074411D03*
X1071065D03*
X1067718D03*
X1064372D03*
X1061025D03*
X1057679D03*
X1054332D03*
X1050986D03*
X1047639D03*
X1044293D03*
X1094490Y579810D03*
X1091143D03*
X1087797D03*
X1084450D03*
X1081104D03*
X1077757D03*
X1074411D03*
X1071065D03*
X1067718D03*
X1064372D03*
X1061025D03*
X1057679D03*
X1054332D03*
X1050986D03*
X1047639D03*
X1044293D03*
X1094490Y561700D03*
X1091143D03*
X1087797D03*
X1084450D03*
X1081104D03*
X1077757D03*
X1074411D03*
X1071065D03*
X1067718D03*
X1064372D03*
X1061025D03*
X1057679D03*
X1054332D03*
X1050986D03*
X1047639D03*
X1044293D03*
X1094490Y542010D03*
X1091143D03*
X1087797D03*
X1084450D03*
X1081104D03*
X1077757D03*
X1074411D03*
X1071065D03*
X1067718D03*
X1064372D03*
X1061025D03*
X1057679D03*
X1054332D03*
X1050986D03*
X1047639D03*
X1044293D03*
X1094490Y617610D03*
X1091143D03*
X1087797D03*
X1084450D03*
X1081104D03*
X1077757D03*
X1074411D03*
X1071065D03*
X1067718D03*
X1064372D03*
X1061025D03*
X1057679D03*
X1054332D03*
X1050986D03*
X1047639D03*
X1044293D03*
X1094490Y599500D03*
X1091143D03*
X1087797D03*
X1084450D03*
X1081104D03*
X1077757D03*
X1074411D03*
X1071065D03*
X1067718D03*
X1064372D03*
X1061025D03*
X1057679D03*
X1054332D03*
X1050986D03*
X1047639D03*
X1044293D03*
X1154726Y3233D03*
X1151380D03*
X1148033D03*
X1144687D03*
X1141340D03*
X1137994D03*
X1134647D03*
X1131301D03*
X1127954D03*
X1124608D03*
X1121261D03*
X1117915D03*
X1114568D03*
X1111222D03*
X1107876D03*
X1104529D03*
X1101183D03*
X1097836D03*
X1154726Y-14877D03*
X1151380D03*
X1148033D03*
X1144687D03*
X1141340D03*
X1137994D03*
X1134647D03*
X1131301D03*
X1127954D03*
X1124608D03*
X1121261D03*
X1117915D03*
X1114568D03*
X1111222D03*
X1107876D03*
X1104529D03*
X1101183D03*
X1097836D03*
X1154726Y22923D03*
X1151380D03*
X1148033D03*
X1144687D03*
X1141340D03*
X1137994D03*
X1134647D03*
X1131301D03*
X1127954D03*
X1124608D03*
X1121261D03*
X1117915D03*
X1114568D03*
X1111222D03*
X1107876D03*
X1104529D03*
X1101183D03*
X1097836D03*
X1154726Y78833D03*
X1151380D03*
X1148033D03*
X1144687D03*
X1141340D03*
X1137994D03*
X1134647D03*
X1131301D03*
X1127954D03*
X1124608D03*
X1121261D03*
X1117915D03*
X1114568D03*
X1111222D03*
X1107876D03*
X1104529D03*
X1101183D03*
X1097836D03*
X1154726Y60723D03*
X1151380D03*
X1148033D03*
X1144687D03*
X1141340D03*
X1137994D03*
X1134647D03*
X1131301D03*
X1127954D03*
X1124608D03*
X1121261D03*
X1117915D03*
X1114568D03*
X1111222D03*
X1107876D03*
X1104529D03*
X1101183D03*
X1097836D03*
X1154726Y41033D03*
X1151380D03*
X1148033D03*
X1144687D03*
X1141340D03*
X1137994D03*
X1134647D03*
X1131301D03*
X1127954D03*
X1124608D03*
X1121261D03*
X1117915D03*
X1114568D03*
X1111222D03*
X1107876D03*
X1104529D03*
X1101183D03*
X1097836D03*
X1154726Y523900D03*
X1151380D03*
X1148033D03*
X1144687D03*
X1141340D03*
X1137994D03*
X1134647D03*
X1131301D03*
X1127954D03*
X1124608D03*
X1121261D03*
X1117915D03*
X1114568D03*
X1111222D03*
X1107876D03*
X1104529D03*
X1101183D03*
X1097836D03*
X1154726Y579810D03*
X1151380D03*
X1148033D03*
X1144687D03*
X1141340D03*
X1137994D03*
X1134647D03*
X1131301D03*
X1127954D03*
X1124608D03*
X1121261D03*
X1117915D03*
X1114568D03*
X1111222D03*
X1107876D03*
X1104529D03*
X1101183D03*
X1097836D03*
X1154726Y561700D03*
X1151380D03*
X1148033D03*
X1144687D03*
X1141340D03*
X1137994D03*
X1134647D03*
X1131301D03*
X1127954D03*
X1124608D03*
X1121261D03*
X1117915D03*
X1114568D03*
X1111222D03*
X1107876D03*
X1104529D03*
X1101183D03*
X1097836D03*
X1154726Y542010D03*
X1151380D03*
X1148033D03*
X1144687D03*
X1141340D03*
X1137994D03*
X1134647D03*
X1131301D03*
X1127954D03*
X1124608D03*
X1121261D03*
X1117915D03*
X1114568D03*
X1111222D03*
X1107876D03*
X1104529D03*
X1101183D03*
X1097836D03*
X1154726Y617610D03*
X1151380D03*
X1148033D03*
X1144687D03*
X1141340D03*
X1137994D03*
X1134647D03*
X1131301D03*
X1127954D03*
X1124608D03*
X1121261D03*
X1117915D03*
X1114568D03*
X1111222D03*
X1107876D03*
X1104529D03*
X1101183D03*
X1097836D03*
X1154726Y599500D03*
X1151380D03*
X1148033D03*
X1144687D03*
X1141340D03*
X1137994D03*
X1134647D03*
X1131301D03*
X1127954D03*
X1124608D03*
X1121261D03*
X1117915D03*
X1114568D03*
X1111222D03*
X1107876D03*
X1104529D03*
X1101183D03*
X1097836D03*
X1218309Y3233D03*
X1214962D03*
X1211616D03*
X1208269D03*
X1204923D03*
X1201576D03*
X1198230D03*
X1194883D03*
X1191537D03*
X1188191D03*
X1184844D03*
X1181498D03*
X1178151D03*
X1174805D03*
X1171458D03*
X1168112D03*
X1164765D03*
X1161419D03*
X1158072D03*
X1218309Y-14877D03*
X1214962D03*
X1211616D03*
X1208269D03*
X1204923D03*
X1201576D03*
X1198230D03*
X1194883D03*
X1191537D03*
X1188191D03*
X1184844D03*
X1181498D03*
X1178151D03*
X1174805D03*
X1171458D03*
X1168112D03*
X1164765D03*
X1161419D03*
X1158072D03*
X1218309Y22923D03*
X1214962D03*
X1211616D03*
X1208269D03*
X1204923D03*
X1201576D03*
X1198230D03*
X1194883D03*
X1191537D03*
X1188191D03*
X1184844D03*
X1181498D03*
X1178151D03*
X1174805D03*
X1171458D03*
X1168112D03*
X1164765D03*
X1161419D03*
X1158072D03*
X1218309Y78833D03*
X1214962D03*
X1211616D03*
X1208269D03*
X1204923D03*
X1201576D03*
X1198230D03*
X1194883D03*
X1191537D03*
X1188191D03*
X1184844D03*
X1181498D03*
X1178151D03*
X1174805D03*
X1171458D03*
X1168112D03*
X1164765D03*
X1161419D03*
X1158072D03*
X1218309Y60723D03*
X1214962D03*
X1211616D03*
X1208269D03*
X1204923D03*
X1201576D03*
X1198230D03*
X1194883D03*
X1191537D03*
X1188191D03*
X1184844D03*
X1181498D03*
X1178151D03*
X1174805D03*
X1171458D03*
X1168112D03*
X1164765D03*
X1161419D03*
X1158072D03*
X1218309Y41033D03*
X1214962D03*
X1211616D03*
X1208269D03*
X1204923D03*
X1201576D03*
X1198230D03*
X1194883D03*
X1191537D03*
X1188191D03*
X1184844D03*
X1181498D03*
X1178151D03*
X1174805D03*
X1171458D03*
X1168112D03*
X1164765D03*
X1161419D03*
X1158072D03*
X1218309Y523900D03*
X1214962D03*
X1211616D03*
X1208269D03*
X1204923D03*
X1201576D03*
X1198230D03*
X1194883D03*
X1191537D03*
X1188191D03*
X1184844D03*
X1181498D03*
X1178151D03*
X1174805D03*
X1171458D03*
X1168112D03*
X1164765D03*
X1161419D03*
X1158072D03*
X1218309Y579810D03*
X1214962D03*
X1211616D03*
X1208269D03*
X1204923D03*
X1201576D03*
X1198230D03*
X1194883D03*
X1191537D03*
X1188191D03*
X1184844D03*
X1181498D03*
X1178151D03*
X1174805D03*
X1171458D03*
X1168112D03*
X1164765D03*
X1161419D03*
X1158072D03*
X1218309Y561700D03*
X1214962D03*
X1211616D03*
X1208269D03*
X1204923D03*
X1201576D03*
X1198230D03*
X1194883D03*
X1191537D03*
X1188191D03*
X1184844D03*
X1181498D03*
X1178151D03*
X1174805D03*
X1171458D03*
X1168112D03*
X1164765D03*
X1161419D03*
X1158072D03*
X1218309Y542010D03*
X1214962D03*
X1211616D03*
X1208269D03*
X1204923D03*
X1201576D03*
X1198230D03*
X1194883D03*
X1191537D03*
X1188191D03*
X1184844D03*
X1181498D03*
X1178151D03*
X1174805D03*
X1171458D03*
X1168112D03*
X1164765D03*
X1161419D03*
X1158072D03*
X1218309Y617610D03*
X1214962D03*
X1211616D03*
X1208269D03*
X1204923D03*
X1201576D03*
X1198230D03*
X1194883D03*
X1191537D03*
X1188191D03*
X1184844D03*
X1181498D03*
X1178151D03*
X1174805D03*
X1171458D03*
X1168112D03*
X1164765D03*
X1161419D03*
X1158072D03*
X1218309Y599500D03*
X1214962D03*
X1211616D03*
X1208269D03*
X1204923D03*
X1201576D03*
X1198230D03*
X1194883D03*
X1191537D03*
X1188191D03*
X1184844D03*
X1181498D03*
X1178151D03*
X1174805D03*
X1171458D03*
X1168112D03*
X1164765D03*
X1161419D03*
X1158072D03*
X1265159Y3233D03*
X1261813D03*
X1258466D03*
X1255120D03*
X1251773D03*
X1248427D03*
X1245080D03*
X1241734D03*
X1238387D03*
X1235041D03*
X1231694D03*
X1228348D03*
X1225002D03*
X1221655D03*
X1265159Y-14877D03*
X1261813D03*
X1258466D03*
X1255120D03*
X1251773D03*
X1248427D03*
X1245080D03*
X1241734D03*
X1238387D03*
X1235041D03*
X1231694D03*
X1228348D03*
X1225002D03*
X1221655D03*
X1265159Y22923D03*
X1261813D03*
X1258466D03*
X1255120D03*
X1251773D03*
X1248427D03*
X1245080D03*
X1241734D03*
X1238387D03*
X1235041D03*
X1231694D03*
X1228348D03*
X1225002D03*
X1221655D03*
X1265159Y78833D03*
X1261813D03*
X1258466D03*
X1255120D03*
X1251773D03*
X1248427D03*
X1245080D03*
X1241734D03*
X1238387D03*
X1235041D03*
X1231694D03*
X1228348D03*
X1225002D03*
X1221655D03*
X1265159Y60723D03*
X1261813D03*
X1258466D03*
X1255120D03*
X1251773D03*
X1248427D03*
X1245080D03*
X1241734D03*
X1238387D03*
X1235041D03*
X1231694D03*
X1228348D03*
X1225002D03*
X1221655D03*
X1265159Y41033D03*
X1261813D03*
X1258466D03*
X1255120D03*
X1251773D03*
X1248427D03*
X1245080D03*
X1241734D03*
X1238387D03*
X1235041D03*
X1231694D03*
X1228348D03*
X1225002D03*
X1221655D03*
X1265159Y523900D03*
X1261813D03*
X1258466D03*
X1255120D03*
X1251773D03*
X1248427D03*
X1245080D03*
X1241734D03*
X1238387D03*
X1235041D03*
X1231694D03*
X1228348D03*
X1225002D03*
X1221655D03*
X1265159Y579810D03*
X1261813D03*
X1258466D03*
X1255120D03*
X1251773D03*
X1248427D03*
X1245080D03*
X1241734D03*
X1238387D03*
X1235041D03*
X1231694D03*
X1228348D03*
X1225002D03*
X1221655D03*
X1265159Y561700D03*
X1261813D03*
X1258466D03*
X1255120D03*
X1251773D03*
X1248427D03*
X1245080D03*
X1241734D03*
X1238387D03*
X1235041D03*
X1231694D03*
X1228348D03*
X1225002D03*
X1221655D03*
X1265159Y542010D03*
X1261813D03*
X1258466D03*
X1255120D03*
X1251773D03*
X1248427D03*
X1245080D03*
X1241734D03*
X1238387D03*
X1235041D03*
X1231694D03*
X1228348D03*
X1225002D03*
X1221655D03*
X1265159Y617610D03*
X1261813D03*
X1258466D03*
X1255120D03*
X1251773D03*
X1248427D03*
X1245080D03*
X1241734D03*
X1238387D03*
X1235041D03*
X1231694D03*
X1228348D03*
X1225002D03*
X1221655D03*
X1265159Y599500D03*
X1261813D03*
X1258466D03*
X1255120D03*
X1251773D03*
X1248427D03*
X1245080D03*
X1241734D03*
X1238387D03*
X1235041D03*
X1231694D03*
X1228348D03*
X1225002D03*
X1221655D03*
G54D232*
X1546953Y273250D03*
Y259750D03*
X1541047D03*
Y273250D03*
G54D241*
X1630534Y336594D03*
X1628566D03*
X1632503D03*
X1636440D03*
X1634472D03*
Y349698D03*
X1636440D03*
X1628566D03*
X1630534D03*
X1632503D03*
G54D40*
X24047Y37443D03*
X24372Y68810D03*
X13947Y544099D03*
Y580099D03*
X138071Y224632D03*
Y288632D03*
Y256632D03*
Y320632D03*
Y352632D03*
Y384632D03*
X787679Y224632D03*
Y256632D03*
Y288632D03*
Y320632D03*
Y352632D03*
X787629Y384632D03*
G54D142*
X678800Y228100D03*
X1337472Y40715D03*
X1351360Y9620D03*
X1355200Y368200D03*
X1351600Y556000D03*
X1356882Y618600D03*
G54D214*
X1519626Y368287D03*
X1492067D03*
X1527500D03*
X1523563D03*
X1511752D03*
X1507815D03*
X1496004D03*
X1503878D03*
X1515689D03*
X1499941D03*
X1527500Y496713D03*
X1511752D03*
X1507815D03*
X1519626D03*
X1523563D03*
X1492067D03*
X1496004D03*
X1499941D03*
X1503878D03*
X1515689D03*
X1558996Y368287D03*
X1531437D03*
X1562933D03*
X1539311D03*
X1535374D03*
X1555059D03*
X1543248D03*
X1547185D03*
X1551122D03*
X1562933Y496713D03*
X1535374D03*
X1547185D03*
X1543248D03*
X1539311D03*
X1531437D03*
X1551122D03*
X1555059D03*
X1558996D03*
G54D205*
X1424210Y551042D03*
Y549467D03*
Y547892D03*
Y546317D03*
Y544742D03*
Y543168D03*
Y541593D03*
Y540018D03*
Y538443D03*
Y536868D03*
X1567850Y612587D03*
Y611012D03*
Y609437D03*
Y607862D03*
Y606287D03*
Y604713D03*
Y603138D03*
Y601563D03*
Y599988D03*
Y598413D03*
G54D31*
X25064Y-11490D03*
X6261Y485075D03*
X-1296Y485081D03*
X1351416Y43361D03*
G54D250*
X1667012Y-14488D03*
G54D13*
X-15748Y101221D03*
Y116969D03*
Y132717D03*
Y148465D03*
Y357362D03*
Y373110D03*
Y388858D03*
Y404606D03*
X12205Y156339D03*
X-4331D03*
X17323Y101221D03*
Y116969D03*
Y132717D03*
Y148465D03*
X787Y101221D03*
Y116969D03*
Y132717D03*
Y148465D03*
X33858Y101221D03*
Y116969D03*
Y132717D03*
Y148465D03*
X28740Y109095D03*
Y124843D03*
Y140591D03*
Y156339D03*
X12205Y109095D03*
Y124843D03*
Y140591D03*
X-4331Y109095D03*
Y124843D03*
Y140591D03*
X17323Y357362D03*
Y373110D03*
Y388858D03*
Y404606D03*
X787Y357362D03*
Y373110D03*
Y388858D03*
Y404606D03*
X33858Y357362D03*
Y373110D03*
Y388858D03*
Y404606D03*
X28740Y365236D03*
Y380984D03*
Y396732D03*
X12205Y365236D03*
Y380984D03*
Y396732D03*
X-4331Y365236D03*
Y380984D03*
Y396732D03*
X12205Y412480D03*
X-4331D03*
X28740D03*
G54D124*
X651950Y261750D03*
G54D251*
X1707500Y121230D03*
G54D233*
X1567064Y522361D03*
X1576796Y523311D03*
X1572495Y598000D03*
G54D134*
X710650Y59390D03*
Y57421D03*
Y55453D03*
Y53484D03*
Y51516D03*
Y49547D03*
Y47579D03*
Y45610D03*
Y43642D03*
Y61358D03*
Y545640D03*
Y543671D03*
Y541703D03*
Y539734D03*
Y537766D03*
Y535797D03*
Y533829D03*
Y531860D03*
Y529892D03*
Y547608D03*
X1370850Y119340D03*
Y117371D03*
Y115403D03*
Y113434D03*
Y111466D03*
Y109497D03*
Y107529D03*
Y105560D03*
Y103592D03*
Y121308D03*
X1365650Y526003D03*
Y524034D03*
Y522066D03*
Y520097D03*
Y518129D03*
Y516160D03*
Y514192D03*
Y529940D03*
Y527971D03*
Y531908D03*
G54D323*
X1962401Y483109D03*
Y494924D03*
Y500829D03*
G54D161*
X1248995Y302830D03*
G54D143*
X715095Y244080D03*
Y236480D03*
X723604Y237024D03*
Y229424D03*
X693061Y228414D03*
Y236014D03*
X732344Y237043D03*
Y229443D03*
X741055Y241836D03*
Y234236D03*
X1384771Y79997D03*
Y87597D03*
X1376912Y79978D03*
Y87578D03*
X1372000Y414300D03*
Y406700D03*
X1364000Y414300D03*
Y406700D03*
X1441554Y578539D03*
Y586139D03*
X1456514Y618961D03*
Y611361D03*
X1448514Y618961D03*
Y611361D03*
X1440514Y618961D03*
Y611361D03*
X1519200Y253300D03*
Y260900D03*
X1526900Y253300D03*
Y260900D03*
X1520650Y275000D03*
Y267400D03*
X1528450Y275000D03*
Y267400D03*
X1603940Y223735D03*
Y231335D03*
X1596340Y223735D03*
Y231335D03*
X1874141Y84412D03*
Y92012D03*
X1881900Y84400D03*
Y92000D03*
X1896900Y79500D03*
Y87100D03*
X1861670Y110400D03*
Y102800D03*
X1929718Y216175D03*
X1938491Y216142D03*
X1929718Y223775D03*
X1938491Y223742D03*
X1938900Y239800D03*
Y232200D03*
X1930600Y239800D03*
Y232200D03*
G54D50*
X23900Y87700D03*
X16300D03*
X36224Y491552D03*
X43824D03*
X36282Y499319D03*
X43882D03*
X722268Y35902D03*
X721192Y528243D03*
X729868Y35902D03*
X728792Y528243D03*
X1390595Y101089D03*
X1382995D03*
X1385800Y512000D03*
X1378200D03*
X1464300Y598500D03*
X1456700D03*
G54D260*
X1734413Y186937D03*
X1731264Y204236D03*
Y186937D03*
X1728114Y204236D03*
Y186937D03*
X1724965Y204236D03*
X1772209D03*
Y186937D03*
X1769059Y204236D03*
Y186937D03*
X1765909Y204236D03*
X1724965Y186937D03*
X1765909D03*
X1762760Y204236D03*
Y186937D03*
X1759610Y204236D03*
Y186937D03*
X1756461Y204236D03*
Y186937D03*
X1753311Y204236D03*
Y186937D03*
X1750161Y204236D03*
X1721815D03*
X1750161Y186937D03*
X1747012Y204236D03*
Y186937D03*
X1743862Y204236D03*
Y186937D03*
X1740713Y204236D03*
Y186937D03*
X1737563Y204236D03*
Y186937D03*
X1734413Y204236D03*
X1721815Y186937D03*
X1759646Y226756D03*
X1756496D03*
X1753347D03*
X1750197D03*
X1747047D03*
X1772244Y244105D03*
X1769095D03*
X1765945D03*
X1762795D03*
X1759646D03*
X1756496D03*
X1743898Y226756D03*
X1753347Y244105D03*
X1750197D03*
X1747047D03*
X1743898D03*
X1740748D03*
X1737599D03*
X1734449D03*
X1740748Y226756D03*
X1737599D03*
X1772244D03*
X1769095D03*
X1765945D03*
X1762795D03*
X1734449D03*
X1835201Y204236D03*
Y186937D03*
X1832051Y204236D03*
Y186937D03*
X1828902Y204236D03*
Y186937D03*
X1825752Y204236D03*
Y186937D03*
X1822602Y204236D03*
Y186937D03*
X1819453Y204236D03*
Y186937D03*
X1816303Y204236D03*
Y186937D03*
X1813154Y204236D03*
Y186937D03*
X1810004Y204236D03*
Y186937D03*
X1806854Y204236D03*
Y186937D03*
X1803705Y204236D03*
Y186937D03*
X1800555Y204236D03*
Y186937D03*
X1797406Y204236D03*
Y186937D03*
X1794256Y204236D03*
Y186937D03*
X1791106Y204236D03*
Y186937D03*
X1787957Y204236D03*
Y186937D03*
X1784807Y204236D03*
Y186937D03*
X1781658Y204236D03*
Y186937D03*
X1778508Y204236D03*
Y186937D03*
X1775358Y204236D03*
Y186937D03*
X1832087Y244105D03*
X1828937D03*
X1825788D03*
X1822638D03*
X1819488D03*
X1816339D03*
X1813189D03*
X1810040D03*
X1806890D03*
X1803740D03*
X1800591D03*
X1797441D03*
X1794292D03*
X1791142D03*
X1787992D03*
X1784843D03*
X1781693D03*
X1778543D03*
X1775394D03*
X1832087Y226756D03*
X1828937D03*
X1825788D03*
X1822638D03*
X1819488D03*
X1816339D03*
X1813189D03*
X1810040D03*
X1806890D03*
X1803740D03*
X1800591D03*
X1797441D03*
X1794292D03*
X1791142D03*
X1787992D03*
X1784843D03*
X1781693D03*
X1778543D03*
X1775394D03*
X1844650Y204236D03*
Y186937D03*
X1841500Y204236D03*
Y186937D03*
X1838350Y204236D03*
Y186937D03*
G54D242*
X1599227Y388133D03*
X1607495Y394433D03*
X1599227D03*
X1607495Y388133D03*
G54D152*
X1267805Y253386D03*
G54D224*
X1472332Y603850D03*
Y605622D03*
Y607393D03*
Y609165D03*
Y610937D03*
Y612708D03*
X1507870Y605118D03*
Y606890D03*
Y608661D03*
Y610433D03*
Y612205D03*
Y613976D03*
G54D215*
X1475098Y397067D03*
Y385256D03*
Y393130D03*
Y389193D03*
Y401004D03*
Y404941D03*
Y420689D03*
Y428563D03*
Y432500D03*
Y440374D03*
Y463996D03*
Y460059D03*
Y456122D03*
Y452185D03*
Y448248D03*
Y444311D03*
Y412815D03*
Y408878D03*
Y416752D03*
Y424626D03*
Y436437D03*
Y467933D03*
Y479744D03*
Y475807D03*
Y471870D03*
X1579902Y393130D03*
Y397067D03*
Y389193D03*
Y385256D03*
Y401004D03*
Y412815D03*
Y456122D03*
Y460059D03*
Y408878D03*
Y404941D03*
Y448248D03*
Y452185D03*
Y444311D03*
Y440374D03*
Y416752D03*
Y432500D03*
Y428563D03*
Y436437D03*
Y424626D03*
Y420689D03*
Y463996D03*
Y467933D03*
Y479744D03*
Y471870D03*
Y475807D03*
G54D314*
X1953740Y235551D03*
G54D32*
X21464Y-11490D03*
X2661Y485075D03*
X-4896Y485081D03*
X1347816Y43361D03*
G54D206*
X1421647Y534305D03*
X1420072D03*
X1418497D03*
X1416922D03*
X1415347D03*
X1413773D03*
X1412198D03*
X1410623D03*
X1409048D03*
X1407473D03*
X1565287Y595850D03*
X1563712D03*
X1562137D03*
X1560562D03*
X1558987D03*
X1557413D03*
X1555838D03*
X1554263D03*
X1552688D03*
X1551113D03*
G54D107*
X170516Y149639D03*
Y182139D03*
X137907Y446215D03*
Y478715D03*
X782990Y154000D03*
Y121500D03*
X782984Y449000D03*
Y481500D03*
G54D14*
X-15354Y109095D03*
Y124843D03*
Y140591D03*
Y156339D03*
Y365236D03*
Y380984D03*
Y396732D03*
Y412480D03*
X22835Y101221D03*
X6299D03*
X-10236D03*
X17716Y109095D03*
X1181D03*
X22835Y116969D03*
X6299D03*
X1181Y124843D03*
X22835Y132717D03*
X1181Y140591D03*
X22835Y148465D03*
X6299D03*
X-10236D03*
X17716Y156339D03*
X1181D03*
X-10236Y116969D03*
X-4725D03*
X23228Y124843D03*
X17716D03*
X-10236Y132717D03*
X-4725D03*
X6299D03*
X11811D03*
X17716Y140591D03*
X23228D03*
X-9843Y156339D03*
X23228Y109095D03*
X6693D03*
Y124843D03*
X-9843Y109095D03*
Y124843D03*
X-4725Y101221D03*
X11811Y148465D03*
Y101221D03*
Y116969D03*
X28346Y101221D03*
Y116969D03*
Y132717D03*
X6693Y140591D03*
X-9843D03*
X28346Y148465D03*
X6693Y156339D03*
X-4725Y148465D03*
X23228Y156339D03*
X22835Y357362D03*
X6299D03*
X-10236D03*
X17716Y365236D03*
X1181D03*
X22835Y373110D03*
X6299D03*
X1181Y380984D03*
X22835Y388858D03*
X1181Y396732D03*
X22835Y404606D03*
X6299D03*
X-10236D03*
Y373110D03*
X-4725D03*
X23228Y380984D03*
X17716D03*
X-10236Y388858D03*
X-4725D03*
X6299D03*
X11811D03*
X17716Y396732D03*
X23228D03*
Y365236D03*
X6693D03*
Y380984D03*
X-9843Y365236D03*
Y380984D03*
X-4725Y357362D03*
X11811Y404606D03*
Y357362D03*
Y373110D03*
X28346Y357362D03*
Y373110D03*
Y388858D03*
X6693Y396732D03*
X-9843D03*
X28346Y404606D03*
X-4725D03*
X17716Y412480D03*
X1181D03*
X-9843D03*
X6693D03*
X23228D03*
G54D170*
X1255969Y462926D03*
X1251312Y459613D03*
G54D305*
X1933849Y132626D03*
Y134594D03*
Y138531D03*
Y140500D03*
X1931550Y132626D03*
Y134594D03*
Y138531D03*
Y140500D03*
G54D23*
X-14690Y551470D03*
X-15570Y579350D03*
X33000Y505500D03*
X-6703Y508598D03*
X12450Y519350D03*
X30428Y485956D03*
X23000Y487500D03*
X15200Y487950D03*
X1483Y474017D03*
X-13000Y529400D03*
X-7335Y537800D03*
X-7383Y573807D03*
X64355Y-5240D03*
X58320Y-6800D03*
X72500Y122000D03*
X90558Y239956D03*
X90040Y262300D03*
X69200Y272600D03*
X104010Y227500D03*
X108879Y266557D03*
X103090Y258300D03*
X100800Y292800D03*
X105400Y283300D03*
X102067Y338387D03*
X76000Y335961D03*
X94810Y318710D03*
X91185Y334900D03*
X96840Y282050D03*
X104070Y342980D03*
X71300Y380710D03*
X100153Y376214D03*
X107300Y360500D03*
X106510Y351100D03*
X78700Y460200D03*
X130150Y203950D03*
X112200Y247200D03*
X112400Y277800D03*
X114120Y220530D03*
X113250Y272650D03*
X109230Y326840D03*
X115350Y315590D03*
X116910Y377860D03*
X209750Y217450D03*
X579900Y117700D03*
X598070Y137040D03*
X598880Y146990D03*
X590950Y144340D03*
X596600Y340900D03*
Y335900D03*
X601381Y400800D03*
X596600Y345900D03*
Y350900D03*
Y365900D03*
Y355900D03*
Y360900D03*
Y370900D03*
X602500Y370800D03*
X596481Y403800D03*
Y398800D03*
X601381Y405800D03*
X596481Y408800D03*
X601300Y410800D03*
X607840Y143940D03*
X606060Y155550D03*
X624600Y287900D03*
X663300Y281820D03*
X610200Y377600D03*
X607900Y370900D03*
X640555Y346055D03*
X628589Y463649D03*
X604900Y424300D03*
Y414300D03*
Y419300D03*
X629359Y469583D03*
X632771Y473269D03*
X605176Y487581D03*
X641107Y471989D03*
X634033Y467638D03*
X642600Y497800D03*
X695300Y17900D03*
X710551Y658D03*
X691400Y25800D03*
X702400Y23700D03*
X711300Y12200D03*
X680700Y24700D03*
X696803Y25820D03*
X714700Y75690D03*
X680880Y271000D03*
X667634Y278953D03*
X680932Y265673D03*
X693529Y250188D03*
X701134Y253677D03*
X713900Y291500D03*
X716900Y305400D03*
X668700Y285000D03*
X695790Y351300D03*
X684126Y369876D03*
X694662Y369884D03*
X670185Y492563D03*
X670400Y497700D03*
X667857Y508142D03*
X672452Y505805D03*
X691000Y512300D03*
X697094Y506828D03*
X702100Y509800D03*
X710760Y488200D03*
X691332Y507278D03*
X716100Y480260D03*
X705800Y576400D03*
X692340Y572850D03*
X698580Y561630D03*
X668260Y594770D03*
X682640Y591000D03*
X777100Y204500D03*
X786709Y200427D03*
X759000Y267000D03*
X734454Y245654D03*
X751300Y247600D03*
X756639Y248780D03*
X751578Y285171D03*
X732700Y293100D03*
X757905Y299400D03*
X761942Y282760D03*
X759900Y309188D03*
X765850Y291010D03*
X760103Y397997D03*
X814849Y205001D03*
X792514Y201290D03*
X797717Y201907D03*
X803134Y202969D03*
X808165Y203529D03*
X818960Y202230D03*
X823206Y192202D03*
X817821Y193049D03*
X813248Y190338D03*
X799224Y192309D03*
X863850Y224150D03*
X1218921Y119054D03*
X1260087Y123945D03*
X1261734Y108836D03*
X1257854Y141843D03*
X1232790Y144530D03*
X1338160Y66800D03*
X1341352Y61072D03*
X1342255Y50160D03*
X1341200Y73400D03*
X1341009Y279356D03*
X1334730Y279747D03*
X1315350Y310550D03*
X1323450Y500420D03*
X1356220Y78330D03*
X1362690Y82705D03*
X1383500Y52100D03*
X1386750Y278000D03*
X1376393Y280244D03*
X1402500Y276550D03*
X1400500Y294975D03*
X1402900Y289900D03*
X1393518Y372918D03*
X1386210Y389910D03*
X1398260Y527120D03*
X1372600Y503973D03*
X1392390Y561630D03*
X1390300Y535100D03*
X1387720Y547690D03*
X1356120Y544446D03*
X1389066Y583080D03*
X1352202Y551402D03*
X1394030Y595500D03*
X1420471Y279778D03*
X1415617Y284527D03*
X1408706Y286801D03*
X1405800Y297138D03*
X1439700Y370300D03*
X1432400Y398000D03*
X1435800Y377000D03*
X1427700Y361100D03*
X1433900Y385500D03*
X1431000Y406500D03*
X1414261Y524820D03*
X1417291Y528974D03*
X1439800Y551490D03*
X1446170Y543700D03*
X1500004Y209210D03*
X1505000Y214000D03*
Y209000D03*
X1489061Y231927D03*
X1500346Y219576D03*
X1467700Y255900D03*
X1495300Y224000D03*
X1506396Y289741D03*
X1514500Y285000D03*
X1479678Y339778D03*
X1577200Y108590D03*
X1586210Y104240D03*
X1580890Y105020D03*
X1581995Y155695D03*
X1588439Y154572D03*
X1580377Y161368D03*
X1544200Y246200D03*
X1528562Y283250D03*
X1572588Y322014D03*
X1576500Y341400D03*
X1559980Y317620D03*
X1562000Y303000D03*
X1536100Y339000D03*
X1552000Y325900D03*
X1586385Y301616D03*
X1582347Y612754D03*
X1587490Y611299D03*
X1593200Y63075D03*
X1647588Y94322D03*
X1650931Y90182D03*
X1630411Y78488D03*
X1640578Y77751D03*
X1602350Y72090D03*
X1627498Y94000D03*
X1594480Y94610D03*
X1601067Y94620D03*
X1643478Y91473D03*
X1635302Y79698D03*
X1621375Y66484D03*
X1645578Y77849D03*
X1607051Y69691D03*
X1619124Y77794D03*
X1591460Y104110D03*
X1592800Y115710D03*
X1592617Y122435D03*
X1615440Y181540D03*
X1630154Y208148D03*
X1592450Y168710D03*
X1604766Y182240D03*
X1591500Y181000D03*
X1629473Y184962D03*
X1592450Y175960D03*
X1643700Y242800D03*
X1602418Y237218D03*
X1648600Y233800D03*
X1650400Y246500D03*
X1649666Y241434D03*
X1637450Y331300D03*
X1649692Y288502D03*
X1643320Y281478D03*
X1641594Y288693D03*
X1647900Y306600D03*
X1604439Y324600D03*
X1629944Y324236D03*
X1633337Y362600D03*
X1649005Y354555D03*
X1625500Y367500D03*
X1625681Y372703D03*
X1647100Y398700D03*
X1625535Y361835D03*
X1635342Y355442D03*
X1614400Y367400D03*
X1599320Y441900D03*
X1613400Y420500D03*
X1624602Y417332D03*
X1606791Y459843D03*
X1598130Y435920D03*
X1643300Y455100D03*
Y448100D03*
X1619984Y448700D03*
X1602450Y451360D03*
X1644040Y428970D03*
X1597885Y449318D03*
X1636700Y427100D03*
X1674400Y78363D03*
X1654406Y94104D03*
X1679980Y94970D03*
X1656737Y77856D03*
X1665909Y93638D03*
X1669800Y84800D03*
X1685578Y94887D03*
X1711869Y81690D03*
X1673400Y59420D03*
X1685622Y103069D03*
X1670055Y96483D03*
X1690870Y104300D03*
X1669405Y200568D03*
X1672120Y190000D03*
X1684550Y187970D03*
X1680901Y170417D03*
X1684600Y194000D03*
X1676624Y185521D03*
X1678400Y179600D03*
X1652218Y182351D03*
X1663434Y185008D03*
X1668519Y185387D03*
X1658000Y185337D03*
X1663800Y320500D03*
X1654900Y302400D03*
X1660700Y351600D03*
X1655600Y346500D03*
X1657984Y403994D03*
X1659100Y362067D03*
X1653310Y405771D03*
X1654400Y455700D03*
X1666200Y447100D03*
X1686542Y497217D03*
X1687152Y491569D03*
X1716050Y67000D03*
X1733600Y65000D03*
X1763500Y91900D03*
X1756200Y78300D03*
X1771646Y90218D03*
X1743200Y80300D03*
X1740400Y69000D03*
X1755400Y87700D03*
X1719486Y506800D03*
X1762450Y497950D03*
X1761900Y504100D03*
X1727600Y555100D03*
X1743486Y607088D03*
X1727666Y609067D03*
X1728341Y617959D03*
X1754300Y605268D03*
X1832830Y76430D03*
X1812700Y133277D03*
X1797720Y150800D03*
X1806400Y143657D03*
X1809867Y126371D03*
X1784100Y117300D03*
X1809900Y108500D03*
X1881700Y141000D03*
X1857620Y135210D03*
X1882528Y102739D03*
X1877372Y102673D03*
X1868100Y149700D03*
X1851860Y143880D03*
X1867351Y103141D03*
X1891350Y144850D03*
X1879938Y185588D03*
X1893586Y196570D03*
X1887737Y196600D03*
X1903648Y76710D03*
X1937100Y146900D03*
X1924100Y127700D03*
X1899790Y110510D03*
X1909620Y117370D03*
X1931250Y114240D03*
X1925300Y102500D03*
X1929377Y118916D03*
X1915854Y118600D03*
X1922526Y122626D03*
X1937300Y104700D03*
X1943835Y145666D03*
X1941449Y139750D03*
X1956890Y211535D03*
X1943803Y167176D03*
X1933290Y201870D03*
X1947666Y190345D03*
X1946500Y180000D03*
X1946925Y163227D03*
X1941012Y191784D03*
X1946200Y172047D03*
X1899092Y231294D03*
X1961890Y211043D03*
Y238405D03*
G54D41*
X30857Y37344D03*
X31182Y68711D03*
X20757Y544000D03*
Y580000D03*
X144881Y224533D03*
Y256533D03*
Y288533D03*
Y320533D03*
Y352533D03*
Y384533D03*
X687243Y214000D03*
X794489Y224533D03*
Y256533D03*
Y320533D03*
Y288533D03*
Y352533D03*
X794439Y384533D03*
X1352332Y-6824D03*
X1352643Y25200D03*
X1354950Y384068D03*
X1356643Y572056D03*
Y603256D03*
G54D125*
X652400Y266849D03*
X681500Y260248D03*
G54D116*
X388187Y-5822D03*
Y31978D03*
Y13078D03*
Y69778D03*
Y50878D03*
Y88678D03*
Y514079D03*
Y532955D03*
Y570755D03*
Y589679D03*
Y551879D03*
Y608555D03*
X1037797Y-5822D03*
Y31978D03*
Y13078D03*
Y69778D03*
Y88678D03*
Y50878D03*
Y514079D03*
Y570755D03*
Y532955D03*
Y589679D03*
Y551879D03*
Y608555D03*
G54D207*
X1466733Y591553D03*
X1502030Y597154D03*
G54D33*
X21522Y11815D03*
X737700Y295500D03*
G54D51*
X14812Y74840D03*
X14487Y43473D03*
X4387Y550129D03*
Y586129D03*
X128511Y262662D03*
Y230662D03*
Y294662D03*
Y326662D03*
Y358662D03*
Y390662D03*
X703613Y207871D03*
X778119Y230662D03*
Y262662D03*
Y326662D03*
Y294662D03*
Y358662D03*
X778069Y390662D03*
X1368702Y-12953D03*
X1369013Y19071D03*
X1371320Y377939D03*
X1373013Y565927D03*
Y597127D03*
G54D162*
X1274699Y333959D03*
G54D234*
X1595602Y3337D03*
Y1369D03*
Y-600D03*
Y-2569D03*
Y-4537D03*
G54D135*
X700484Y41350D03*
X702453D03*
X704421D03*
X706390D03*
X708358D03*
X690642D03*
X692610D03*
X694579D03*
X696547D03*
X698516D03*
X700484Y527600D03*
X702453D03*
X704421D03*
X706390D03*
X708358D03*
X690642D03*
X692610D03*
X694579D03*
X696547D03*
X698516D03*
X1360684Y101300D03*
X1362653D03*
X1364621D03*
X1366590D03*
X1368558D03*
X1350842D03*
X1352810D03*
X1354779D03*
X1356747D03*
X1358716D03*
X1355484Y511900D03*
X1357453D03*
X1359421D03*
X1361390D03*
X1363358D03*
X1345642D03*
X1347610D03*
X1349579D03*
X1351547D03*
X1353516D03*
G54D315*
X1918885Y224779D03*
Y235941D03*
G54D117*
X380892Y91500D03*
Y97000D03*
Y505756D03*
Y511256D03*
X642823Y131000D03*
Y136500D03*
X647561Y131000D03*
Y136500D03*
X1030500Y91500D03*
Y97000D03*
Y505756D03*
Y511256D03*
G54D306*
X1932700Y136563D03*
G54D153*
X1254526Y258759D03*
G54D270*
X1761339Y536791D03*
X1757402D03*
X1753465D03*
X1749528D03*
X1745591D03*
X1741654D03*
X1761339D03*
X1757402D03*
X1753465D03*
X1749528D03*
X1745591D03*
X1741654D03*
G54D180*
X1284290Y227739D03*
G54D225*
X1586547Y-6702D03*
X1592531D03*
G54D144*
X684219Y333516D03*
Y331547D03*
Y329578D03*
Y327609D03*
Y325640D03*
Y323671D03*
Y321702D03*
Y319733D03*
Y317764D03*
Y315795D03*
Y313826D03*
Y311857D03*
Y309888D03*
Y307919D03*
Y305950D03*
Y303981D03*
G54D324*
X1970071Y540467D03*
X1963071D03*
X1970071Y545979D03*
X1963071D03*
G54D42*
X20515Y31338D03*
X20840Y62705D03*
X10415Y537994D03*
Y573994D03*
X134539Y218527D03*
Y250527D03*
Y282527D03*
Y314527D03*
Y346527D03*
Y378527D03*
X697585Y220006D03*
X784147Y218527D03*
Y250527D03*
Y314527D03*
Y282527D03*
Y346527D03*
X784097Y378527D03*
X1362674Y-818D03*
X1362985Y31206D03*
X1365292Y390074D03*
X1366985Y578062D03*
Y609262D03*
G54D261*
X1741609Y167494D03*
G54D252*
X1712012Y195587D03*
G54D24*
X-13780Y598560D03*
X-3937Y-43307D03*
Y646063D03*
X1956693Y-43307D03*
Y646063D03*
G54D60*
X40512Y458744D03*
G54D216*
X1475098Y493532D03*
X1478279Y496713D03*
X1579902Y371468D03*
X1576721Y368287D03*
Y496713D03*
X1579902Y493532D03*
X1602717Y104467D03*
X1605867Y110766D03*
X1602717Y107617D03*
X1605867Y104467D03*
Y107617D03*
X1609016Y110766D03*
Y104467D03*
Y107617D03*
X1602717Y110766D03*
Y170609D03*
Y167459D03*
X1605867D03*
Y170609D03*
X1602717Y164310D03*
X1609016D03*
X1605867D03*
X1609016Y167459D03*
Y170609D03*
X1668859Y104467D03*
Y110766D03*
X1662560D03*
X1665709D03*
Y107617D03*
X1662560D03*
X1665709Y104467D03*
X1668859Y107617D03*
X1662560Y104467D03*
X1668859Y170609D03*
X1665709Y167459D03*
X1668859D03*
Y164310D03*
X1662560D03*
X1665709D03*
Y170609D03*
X1662560D03*
Y167459D03*
G54D171*
X1239184Y461227D03*
X1254389Y470270D03*
G54D243*
X1599194Y429620D03*
G54D126*
X652700Y275600D03*
X693962Y313316D03*
X689000Y312366D03*
G54D108*
X149920Y137452D03*
Y108452D03*
G54D15*
X-15300Y255000D03*
X13700D03*
G54D34*
X25122Y11815D03*
X741300Y295500D03*
G54D70*
X1013Y513450D03*
X2588D03*
X4163D03*
X5738D03*
X7313D03*
X8887D03*
X10462D03*
X12037D03*
X13612D03*
X15187D03*
X659013Y272650D03*
X660588D03*
X662163D03*
X663738D03*
X665313D03*
X666887D03*
X668462D03*
X670037D03*
X671612D03*
X673187D03*
X1349913Y70150D03*
X1351488D03*
X1353063D03*
X1354638D03*
X1356213D03*
X1357787D03*
X1359362D03*
X1360937D03*
X1362512D03*
X1364087D03*
G54D235*
X1632000Y47500D03*
Y64500D03*
G54D127*
X649819Y303981D03*
Y305950D03*
Y307919D03*
Y309888D03*
Y311857D03*
Y313826D03*
Y315795D03*
Y317764D03*
Y319733D03*
Y321702D03*
Y323671D03*
Y325640D03*
Y327609D03*
Y329578D03*
Y331547D03*
Y333516D03*
G54D154*
X1252354Y276226D03*
G54D181*
X1285536Y330531D03*
G54D43*
X14487Y33945D03*
X14812Y65312D03*
X4387Y540601D03*
Y576601D03*
X128511Y221134D03*
Y253134D03*
Y285134D03*
Y317134D03*
Y349134D03*
Y381134D03*
X703613Y217399D03*
X778119Y221134D03*
Y253134D03*
Y317134D03*
Y285134D03*
Y349134D03*
X778069Y381134D03*
X1368702Y-3425D03*
X1369013Y28599D03*
X1371320Y387467D03*
X1373013Y575455D03*
Y606655D03*
G54D253*
X1698611Y192179D03*
Y183518D03*
X1692312D03*
Y192179D03*
G54D163*
X1268614Y341717D03*
G54D145*
X687527Y379176D03*
X679847Y402676D03*
X687527D03*
X695207D03*
Y379176D03*
X679847D03*
X692647D03*
X690087D03*
X684967D03*
X682407D03*
X692647Y402676D03*
X690087D03*
X684967D03*
X682407D03*
G54D226*
X1583398Y-4537D03*
Y-2569D03*
Y-600D03*
Y1369D03*
Y3337D03*
G54D118*
X600150Y122700D03*
Y117700D03*
Y112700D03*
X589650Y117700D03*
Y112700D03*
Y122700D03*
X1241406Y119155D03*
Y114155D03*
Y109155D03*
X1230906Y114155D03*
Y109155D03*
Y119155D03*
G54D109*
X111093Y122603D03*
X118935D03*
Y126345D03*
Y118861D03*
X111093D03*
Y126345D03*
X718916Y92446D03*
X711074D03*
Y96188D03*
X718916D03*
Y99930D03*
X711074D03*
X727916Y499895D03*
X735758D03*
Y503637D03*
Y496153D03*
X727916D03*
Y503637D03*
G54D307*
X1955531Y155984D03*
Y152047D03*
Y148110D03*
Y144173D03*
Y175669D03*
Y171732D03*
Y167795D03*
Y163858D03*
Y159921D03*
Y191417D03*
Y187480D03*
Y183543D03*
Y179606D03*
G54D280*
X1822758Y542204D03*
X1800207Y540236D03*
X1822758D03*
X1800207Y538267D03*
X1800206Y587480D03*
X1822757D03*
X1800206Y585511D03*
X1822757D03*
X1800206Y583543D03*
X1822757D03*
X1800206Y581574D03*
X1822758Y538267D03*
X1822757Y581574D03*
X1800206Y579606D03*
X1822757D03*
X1800206Y577637D03*
X1822757D03*
X1800206Y575669D03*
X1822757D03*
X1800206Y573700D03*
X1822757D03*
X1800206Y571732D03*
X1800207Y536299D03*
X1822757Y571732D03*
X1800206Y569763D03*
X1822757D03*
X1800206Y567795D03*
X1822757D03*
X1800206Y565826D03*
X1822757D03*
X1800206Y563858D03*
X1822757D03*
X1800207Y561889D03*
X1822758Y536299D03*
Y561889D03*
X1800207Y559921D03*
X1822758D03*
X1800207Y557952D03*
X1822758D03*
X1800207Y555984D03*
X1822758D03*
X1800207Y554015D03*
X1822758D03*
X1800207Y552047D03*
Y534330D03*
X1822758Y552047D03*
X1800207Y550078D03*
X1822758D03*
X1800207Y548110D03*
X1822758D03*
X1800207Y546141D03*
X1822758D03*
X1800207Y544173D03*
X1822758D03*
X1800207Y542204D03*
X1822758Y534330D03*
X1800206Y591417D03*
X1822757D03*
X1800206Y589448D03*
X1822757D03*
G54D316*
X1933900Y487210D03*
Y482090D03*
Y484650D03*
Y479530D03*
X1923900Y487210D03*
Y484650D03*
Y482090D03*
Y479530D03*
G54D217*
X1481800Y582200D03*
Y553700D03*
G54D136*
X688350Y61358D03*
Y59390D03*
Y57421D03*
Y55453D03*
Y53484D03*
Y51516D03*
Y49547D03*
Y47579D03*
Y45610D03*
Y43642D03*
Y547608D03*
Y545640D03*
Y543671D03*
Y541703D03*
Y539734D03*
Y537766D03*
Y535797D03*
Y533829D03*
Y531860D03*
Y529892D03*
X1348550Y121308D03*
Y119340D03*
Y117371D03*
Y115403D03*
Y113434D03*
Y111466D03*
Y109497D03*
Y107529D03*
Y105560D03*
Y103592D03*
X1343350Y526003D03*
Y524034D03*
Y522066D03*
Y520097D03*
Y518129D03*
Y516160D03*
Y514192D03*
Y531908D03*
Y529940D03*
Y527971D03*
G54D262*
X1741609Y173094D03*
G54D325*
X1965000Y561500D03*
Y583000D03*
Y604500D03*
G54D25*
X30500Y-42250D03*
Y-52250D03*
X50500Y-42250D03*
X70500D03*
X90500D03*
X110500D03*
X50500Y-52250D03*
X70500D03*
X90500D03*
X110500D03*
X60512Y467244D03*
X130500Y-42250D03*
Y-52250D03*
X457246Y-52301D03*
Y-42301D03*
X477246Y-52301D03*
Y-42301D03*
X497246Y-52301D03*
Y-42301D03*
X517246Y-52301D03*
Y-42301D03*
X537246Y-52301D03*
Y-42301D03*
X557246Y-52301D03*
Y-42301D03*
X788984Y-52057D03*
Y-42057D03*
X808984Y-52057D03*
Y-42057D03*
X828984Y-52057D03*
Y-42057D03*
X848984Y-52057D03*
Y-42057D03*
X868984Y-52057D03*
Y-42057D03*
X888984Y-52057D03*
Y-42057D03*
X1125583Y-52285D03*
Y-42285D03*
X1145583Y-52285D03*
Y-42285D03*
X1382258Y-52257D03*
Y-42257D03*
X1402258Y-52257D03*
Y-42257D03*
X1422258Y-52257D03*
Y-42257D03*
X1442258Y-52257D03*
Y-42257D03*
X1891086Y592105D03*
X1904100Y493000D03*
X1968000Y568500D03*
Y554500D03*
Y590000D03*
Y576000D03*
Y597500D03*
Y611500D03*
G54D52*
X-7874Y216181D03*
Y325315D03*
G54D271*
X1733096Y588640D03*
X1727190D03*
X1895673Y155900D03*
X1893705D03*
X1891736D03*
X1897642D03*
X1921264D03*
X1905516D03*
X1911421D03*
X1913390D03*
X1917327D03*
X1915358D03*
X1919295D03*
X1899610D03*
X1903547D03*
X1909453D03*
X1901579D03*
X1907484D03*
G54D208*
X1526871Y23968D03*
X1800986Y523267D03*
X1800985Y602503D03*
X1809665Y618663D03*
X1819665D03*
X1829665D03*
X1881595Y23968D03*
G54D61*
X-4488Y425472D03*
X99980Y136909D03*
G54D172*
X1261381Y427008D03*
X1253042Y422650D03*
G54D190*
X1462000Y-5000D03*
Y-15000D03*
X1452000Y-5000D03*
Y-15000D03*
X1442000Y-5000D03*
X1525000Y-15000D03*
X1515000D03*
X1482000D03*
X1472000Y-5000D03*
Y-15000D03*
X1492000Y-5000D03*
Y-15000D03*
X1482000Y-5000D03*
X1575000Y-15000D03*
X1565000D03*
X1555000D03*
X1545000D03*
X1535000D03*
X1713503Y-5000D03*
Y-15000D03*
X1703503Y-5000D03*
X1743503Y-15000D03*
X1733503Y-5000D03*
Y-15000D03*
X1723503Y-5000D03*
Y-15000D03*
X1753503Y-5000D03*
Y-15000D03*
X1743503Y-5000D03*
X1769504D03*
X1809504Y-15000D03*
X1799504Y-5000D03*
Y-15000D03*
X1789504Y-5000D03*
Y-15000D03*
X1779504Y-5000D03*
Y-15000D03*
X1819504Y-5000D03*
Y-15000D03*
X1809504Y-5000D03*
G54D244*
X1638131Y525946D03*
Y475946D03*
G54D16*
X-14488Y434094D03*
X-4488D03*
X5512D03*
X15512D03*
X89980Y145531D03*
X99980D03*
X109980D03*
X119980D03*
G54D326*
G01X548049Y-193422D02*
Y-210922D01*
G01X543027Y-193422D02*
X553071D01*
G01X565549Y-199256D02*
Y-210922D01*
G01Y-194589D02*
X565112Y-194297D01*
Y-193714D01*
X565549Y-193422D01*
X565986Y-193714D01*
Y-194297D01*
X565549Y-194589D01*
G01X583049Y-210922D02*
X581739Y-210630D01*
X580429Y-209464D01*
X579555Y-207422D01*
X579119Y-205089D01*
X579555Y-202755D01*
X580429Y-200714D01*
X581739Y-199547D01*
X583049Y-199256D01*
X584359Y-199547D01*
X585669Y-200714D01*
X586542Y-202755D01*
X586761Y-205089D01*
X586542Y-207422D01*
X585669Y-209464D01*
X584359Y-210630D01*
X583049Y-210922D01*
G01X597492Y-215297D02*
X599021Y-216464D01*
X600767Y-216755D01*
X602295Y-216464D01*
X603606Y-215006D01*
X604479Y-212964D01*
Y-199256D01*
G01Y-201589D02*
X603606Y-200422D01*
X602295Y-199547D01*
X600767Y-199256D01*
X599021Y-199839D01*
X597929Y-201005D01*
X597055Y-203047D01*
X596619Y-205089D01*
X596837Y-206839D01*
X597711Y-208881D01*
X599021Y-210339D01*
X600767Y-210922D01*
X602077Y-210630D01*
X603606Y-209464D01*
X604479Y-208298D01*
G01X621979Y-210922D02*
Y-199256D01*
G01Y-201297D02*
X621106Y-200131D01*
X619795Y-199547D01*
X618267Y-199256D01*
X616739Y-199839D01*
X615429Y-201005D01*
X614555Y-202755D01*
X614119Y-205089D01*
X614555Y-207422D01*
X615429Y-209172D01*
X616739Y-210339D01*
X618267Y-210922D01*
X619795Y-210630D01*
X621106Y-209756D01*
X621979Y-208589D01*
G01X648682Y-210922D02*
Y-193422D01*
X653922D01*
X655669Y-194297D01*
X656979Y-196339D01*
X657416Y-198672D01*
X656979Y-201005D01*
X655887Y-202755D01*
X653922Y-203631D01*
X648682D01*
G01X674479Y-210922D02*
Y-199256D01*
G01Y-201297D02*
X673606Y-200131D01*
X672295Y-199547D01*
X670767Y-199256D01*
X669239Y-199839D01*
X667929Y-201005D01*
X667055Y-202755D01*
X666619Y-205089D01*
X667055Y-207422D01*
X667929Y-209172D01*
X669239Y-210339D01*
X670767Y-210922D01*
X672295Y-210630D01*
X673606Y-209756D01*
X674479Y-208589D01*
G01X684774Y-208881D02*
X685866Y-210047D01*
X687394Y-210922D01*
X688704D01*
X690014Y-210339D01*
X690887Y-209464D01*
X691324Y-208298D01*
X691106Y-206547D01*
X690232Y-205672D01*
X686302Y-203922D01*
X685429Y-201880D01*
X685866Y-200422D01*
X686739Y-199547D01*
X688049Y-199256D01*
X689359Y-199547D01*
X690669Y-200422D01*
G01X702274Y-208881D02*
X703366Y-210047D01*
X704894Y-210922D01*
X706204D01*
X707514Y-210339D01*
X708387Y-209464D01*
X708824Y-208298D01*
X708606Y-206547D01*
X707732Y-205672D01*
X703802Y-203922D01*
X702929Y-201880D01*
X703366Y-200422D01*
X704239Y-199547D01*
X705549Y-199256D01*
X706859Y-199547D01*
X708169Y-200422D01*
G01X735746Y-210922D02*
Y-193422D01*
X740112D01*
X741859Y-194297D01*
X743169Y-195464D01*
X744261Y-197213D01*
X745134Y-199256D01*
X745352Y-202172D01*
X745134Y-205089D01*
X744261Y-207131D01*
X743169Y-208881D01*
X741859Y-210047D01*
X740112Y-210922D01*
X735746D01*
G01X752590Y-193422D02*
X758049Y-210922D01*
X763508Y-193422D01*
G01X775549D02*
Y-210922D01*
G01X770527Y-193422D02*
X780571D01*
G01X804872Y-210922D02*
Y-193422D01*
X810549Y-208005D01*
X816226Y-193422D01*
Y-210922D01*
G01X829795Y-201589D02*
X830669Y-200714D01*
X831324Y-199256D01*
X831761Y-197213D01*
X831324Y-195464D01*
X830451Y-194297D01*
X828922Y-193422D01*
X823027D01*
Y-210922D01*
X830232D01*
X831761Y-209756D01*
X832634Y-208005D01*
X833071Y-205964D01*
X832634Y-203922D01*
X831324Y-202172D01*
X829795Y-201589D01*
X823027D01*
G01X647372Y-165922D02*
Y-148422D01*
X653049Y-163005D01*
X658726Y-148422D01*
Y-165922D01*
G01X670549D02*
X669239Y-165630D01*
X667929Y-164464D01*
X667055Y-162422D01*
X666619Y-160089D01*
X667055Y-157755D01*
X667929Y-155714D01*
X669239Y-154547D01*
X670549Y-154256D01*
X671859Y-154547D01*
X673169Y-155714D01*
X674042Y-157755D01*
X674261Y-160089D01*
X674042Y-162422D01*
X673169Y-164464D01*
X671859Y-165630D01*
X670549Y-165922D01*
G01X691979Y-148422D02*
Y-165922D01*
G01Y-163298D02*
X691106Y-164756D01*
X689795Y-165630D01*
X688267Y-165922D01*
X686521Y-165339D01*
X685211Y-163881D01*
X684337Y-162131D01*
X684119Y-160089D01*
X684337Y-158047D01*
X685211Y-156297D01*
X686521Y-154839D01*
X688267Y-154256D01*
X689795Y-154547D01*
X690887Y-155131D01*
X691979Y-156297D01*
G01X702274Y-158047D02*
X709261D01*
X708606Y-156005D01*
X707514Y-154839D01*
X705986Y-154256D01*
X704457Y-154547D01*
X703147Y-155422D01*
X702274Y-157464D01*
X701837Y-159214D01*
Y-160964D01*
X702274Y-162714D01*
X703366Y-164464D01*
X704676Y-165630D01*
X706204Y-165922D01*
X707732Y-165339D01*
X709261Y-163589D01*
G01X723049Y-165922D02*
Y-148422D01*
G01X975549Y-210922D02*
Y-193422D01*
X972929Y-196922D01*
G01Y-210922D02*
X978169D01*
G01X988246Y-208298D02*
X989555Y-209756D01*
X991084Y-210630D01*
X993049Y-210922D01*
X995014Y-210339D01*
X996542Y-209172D01*
X997634Y-207131D01*
X997852Y-204797D01*
X997416Y-202464D01*
X996324Y-201005D01*
X994795Y-199839D01*
X993267Y-199547D01*
X991739Y-199839D01*
X989774Y-201005D01*
X990429Y-193422D01*
X996324D01*
G01X1010549Y-210922D02*
Y-193422D01*
X1007929Y-196922D01*
G01Y-210922D02*
X1013169D01*
G01X1023901Y-196339D02*
X1025211Y-194589D01*
X1026739Y-193714D01*
X1028486Y-193422D01*
X1030669Y-194005D01*
X1032197Y-195464D01*
X1032634Y-197213D01*
X1032416Y-198964D01*
X1031542Y-200422D01*
X1027176Y-203339D01*
X1025211Y-205380D01*
X1023901Y-208298D01*
X1023464Y-210922D01*
X1032634D01*
G01X1041401Y-203631D02*
X1042929Y-201589D01*
X1044239Y-200422D01*
X1045986Y-199839D01*
X1047514Y-200422D01*
X1048606Y-201589D01*
X1049479Y-203339D01*
X1049697Y-205380D01*
X1049479Y-207131D01*
X1048606Y-208881D01*
X1047295Y-210339D01*
X1045767Y-210922D01*
X1044021Y-210339D01*
X1042492Y-208589D01*
X1041619Y-205964D01*
X1041401Y-203047D01*
X1041837Y-199256D01*
X1042492Y-197213D01*
X1043584Y-195172D01*
X1045112Y-193714D01*
X1046641Y-193422D01*
X1048169Y-194005D01*
X1049261Y-195464D01*
G01X962432Y-165922D02*
Y-148422D01*
X967672D01*
X969419Y-149297D01*
X970729Y-151339D01*
X971166Y-153672D01*
X970729Y-156005D01*
X969637Y-157755D01*
X967672Y-158631D01*
X962432D01*
G01X989102Y-149881D02*
X987792Y-149005D01*
X986264Y-148422D01*
X984517D01*
X982552Y-149297D01*
X981024Y-150755D01*
X979932Y-152506D01*
X979059Y-155422D01*
X978840Y-158047D01*
X979277Y-160672D01*
X979932Y-162422D01*
X981242Y-164172D01*
X982771Y-165339D01*
X984299Y-165922D01*
X985827D01*
X987356Y-165339D01*
X988666Y-164464D01*
X989758Y-163298D01*
G01X1003545Y-156589D02*
X1004419Y-155714D01*
X1005074Y-154256D01*
X1005511Y-152213D01*
X1005074Y-150464D01*
X1004201Y-149297D01*
X1002672Y-148422D01*
X996777D01*
Y-165922D01*
X1003982D01*
X1005511Y-164756D01*
X1006384Y-163005D01*
X1006821Y-160964D01*
X1006384Y-158922D01*
X1005074Y-157172D01*
X1003545Y-156589D01*
X996777D01*
G01X1012749Y-171755D02*
X1025849D01*
G01X1031777Y-165922D02*
Y-148422D01*
X1041821Y-165922D01*
Y-148422D01*
G01X1054299Y-165922D02*
X1052552Y-165630D01*
X1051024Y-164464D01*
X1049714Y-162714D01*
X1048840Y-160672D01*
X1048404Y-158339D01*
Y-156005D01*
X1048840Y-153672D01*
X1049714Y-151630D01*
X1051024Y-149881D01*
X1052552Y-148714D01*
X1054299Y-148422D01*
X1056045Y-148714D01*
X1057574Y-149881D01*
X1058884Y-151630D01*
X1059758Y-153672D01*
X1060194Y-156005D01*
Y-158339D01*
X1059758Y-160672D01*
X1058884Y-162714D01*
X1057574Y-164464D01*
X1056045Y-165630D01*
X1054299Y-165922D01*
G01X1128099Y-210922D02*
Y-193422D01*
X1125479Y-196922D01*
G01Y-210922D02*
X1130719D01*
G01X1147345Y-201589D02*
X1148219Y-200714D01*
X1148874Y-199256D01*
X1149311Y-197213D01*
X1148874Y-195464D01*
X1148001Y-194297D01*
X1146472Y-193422D01*
X1140577D01*
Y-210922D01*
X1147782D01*
X1149311Y-209756D01*
X1150184Y-208005D01*
X1150621Y-205964D01*
X1150184Y-203922D01*
X1148874Y-202172D01*
X1147345Y-201589D01*
X1140577D01*
G01X1105140Y-148422D02*
X1110599Y-165922D01*
X1116058Y-148422D01*
G01X1132466Y-165922D02*
X1123732D01*
Y-148422D01*
X1132466D01*
G01X1128972Y-156880D02*
X1123732D01*
G01X1141232Y-165922D02*
Y-148422D01*
X1146691D01*
X1148437Y-149297D01*
X1149529Y-150464D01*
X1149966Y-152797D01*
X1149529Y-155131D01*
X1148219Y-156589D01*
X1146691Y-157464D01*
X1141232D01*
G01X1146691D02*
X1149966Y-165922D01*
G01X1163099Y-166505D02*
X1162662Y-166214D01*
Y-165630D01*
X1163099Y-165339D01*
X1163536Y-165630D01*
Y-166214D01*
X1163099Y-166505D01*
G01X1243049Y-193422D02*
Y-210922D01*
G01X1238027Y-193422D02*
X1248071D01*
G01X1254872Y-210922D02*
Y-193422D01*
X1260549Y-208005D01*
X1266226Y-193422D01*
Y-210922D01*
G01X1272590D02*
X1278049Y-193422D01*
X1283508Y-210922D01*
G01X1281542Y-204797D02*
X1274555D01*
G01X1290964Y-208589D02*
X1292711Y-210047D01*
X1294676Y-210922D01*
X1296422D01*
X1298169Y-210047D01*
X1299479Y-208589D01*
X1300134Y-206547D01*
X1299697Y-204506D01*
X1298606Y-202755D01*
X1296641Y-201589D01*
X1294021Y-201005D01*
X1292492Y-199839D01*
X1291837Y-197797D01*
X1292274Y-195755D01*
X1293366Y-194297D01*
X1294894Y-193422D01*
X1296422D01*
X1297951Y-194005D01*
X1299261Y-195464D01*
G01X1308246Y-210922D02*
Y-193422D01*
G01X1316542D02*
X1308246Y-204214D01*
G01X1317852Y-210922D02*
X1311957Y-199256D01*
G01X1238682Y-148422D02*
Y-165922D01*
X1247416D01*
G01X1264479D02*
Y-154256D01*
G01Y-156297D02*
X1263606Y-155131D01*
X1262295Y-154547D01*
X1260767Y-154256D01*
X1259239Y-154839D01*
X1257929Y-156005D01*
X1257055Y-157755D01*
X1256619Y-160089D01*
X1257055Y-162422D01*
X1257929Y-164172D01*
X1259239Y-165339D01*
X1260767Y-165922D01*
X1262295Y-165630D01*
X1263606Y-164756D01*
X1264479Y-163589D01*
G01X1273464Y-171172D02*
X1274774Y-171755D01*
X1276521Y-171172D01*
X1277612Y-170006D01*
X1278486Y-168547D01*
X1279795Y-163881D01*
X1282634Y-154256D01*
G01X1275647D02*
X1279795Y-163881D01*
G01X1292274Y-158047D02*
X1299261D01*
X1298606Y-156005D01*
X1297514Y-154839D01*
X1295986Y-154256D01*
X1294457Y-154547D01*
X1293147Y-155422D01*
X1292274Y-157464D01*
X1291837Y-159214D01*
Y-160964D01*
X1292274Y-162714D01*
X1293366Y-164464D01*
X1294676Y-165630D01*
X1296204Y-165922D01*
X1297732Y-165339D01*
X1299261Y-163589D01*
G01X1309992Y-165922D02*
Y-154256D01*
G01Y-156589D02*
X1311084Y-155422D01*
X1312176Y-154547D01*
X1313704Y-154256D01*
X1314795Y-154547D01*
X1316106Y-155422D01*
G01X1380796Y-165922D02*
Y-148422D01*
X1385162D01*
X1386909Y-149297D01*
X1388219Y-150464D01*
X1389311Y-152213D01*
X1390184Y-154256D01*
X1390402Y-157172D01*
X1390184Y-160089D01*
X1389311Y-162131D01*
X1388219Y-163881D01*
X1386909Y-165047D01*
X1385162Y-165922D01*
X1380796D01*
G01X1399824Y-158047D02*
X1406811D01*
X1406156Y-156005D01*
X1405064Y-154839D01*
X1403536Y-154256D01*
X1402007Y-154547D01*
X1400697Y-155422D01*
X1399824Y-157464D01*
X1399387Y-159214D01*
Y-160964D01*
X1399824Y-162714D01*
X1400916Y-164464D01*
X1402226Y-165630D01*
X1403754Y-165922D01*
X1405282Y-165339D01*
X1406811Y-163589D01*
G01X1417324Y-163881D02*
X1418416Y-165047D01*
X1419944Y-165922D01*
X1421254D01*
X1422564Y-165339D01*
X1423437Y-164464D01*
X1423874Y-163298D01*
X1423656Y-161547D01*
X1422782Y-160672D01*
X1418852Y-158922D01*
X1417979Y-156880D01*
X1418416Y-155422D01*
X1419289Y-154547D01*
X1420599Y-154256D01*
X1421909Y-154547D01*
X1423219Y-155422D01*
G01X1438099Y-154256D02*
Y-165922D01*
G01Y-149589D02*
X1437662Y-149297D01*
Y-148714D01*
X1438099Y-148422D01*
X1438536Y-148714D01*
Y-149297D01*
X1438099Y-149589D01*
G01X1452542Y-170297D02*
X1454071Y-171464D01*
X1455817Y-171755D01*
X1457345Y-171464D01*
X1458656Y-170006D01*
X1459529Y-167964D01*
Y-154256D01*
G01Y-156589D02*
X1458656Y-155422D01*
X1457345Y-154547D01*
X1455817Y-154256D01*
X1454071Y-154839D01*
X1452979Y-156005D01*
X1452105Y-158047D01*
X1451669Y-160089D01*
X1451887Y-161839D01*
X1452761Y-163881D01*
X1454071Y-165339D01*
X1455817Y-165922D01*
X1457127Y-165630D01*
X1458656Y-164464D01*
X1459529Y-163298D01*
G01X1469387Y-165922D02*
Y-154256D01*
G01Y-157172D02*
X1470261Y-155714D01*
X1471571Y-154547D01*
X1473317Y-154256D01*
X1474845Y-154547D01*
X1476156Y-155714D01*
X1476811Y-157755D01*
Y-165922D01*
G01X1487324Y-158047D02*
X1494311D01*
X1493656Y-156005D01*
X1492564Y-154839D01*
X1491036Y-154256D01*
X1489507Y-154547D01*
X1488197Y-155422D01*
X1487324Y-157464D01*
X1486887Y-159214D01*
Y-160964D01*
X1487324Y-162714D01*
X1488416Y-164464D01*
X1489726Y-165630D01*
X1491254Y-165922D01*
X1492782Y-165339D01*
X1494311Y-163589D01*
G01X1505042Y-165922D02*
Y-154256D01*
G01Y-156589D02*
X1506134Y-155422D01*
X1507226Y-154547D01*
X1508754Y-154256D01*
X1509845Y-154547D01*
X1511156Y-155422D01*
G01X1426729Y-193422D02*
X1431969D01*
G01X1429349D02*
Y-210922D01*
G01X1426729D02*
X1431969D01*
G01X1441390Y-193422D02*
X1446849Y-210922D01*
X1452308Y-193422D01*
G01X1464349Y-210922D02*
Y-203047D01*
X1459982Y-193422D01*
G01X1468716D02*
X1464349Y-203047D01*
G01X1467485Y338189D02*
G03I-12800J0D01*
G01X1551799Y-193422D02*
X1550052Y-194005D01*
X1548742Y-195464D01*
X1547869Y-197213D01*
X1547214Y-199547D01*
X1546996Y-202172D01*
X1547214Y-204797D01*
X1547869Y-207131D01*
X1548742Y-208881D01*
X1550052Y-210339D01*
X1551799Y-210922D01*
X1553545Y-210339D01*
X1554856Y-208881D01*
X1555729Y-207131D01*
X1556384Y-204797D01*
X1556602Y-202172D01*
X1556384Y-199547D01*
X1555729Y-197213D01*
X1554856Y-195464D01*
X1553545Y-194005D01*
X1551799Y-193422D01*
G01X1565151Y-196339D02*
X1566461Y-194589D01*
X1567989Y-193714D01*
X1569736Y-193422D01*
X1571919Y-194005D01*
X1573447Y-195464D01*
X1573884Y-197213D01*
X1573666Y-198964D01*
X1572792Y-200422D01*
X1568426Y-203339D01*
X1566461Y-205380D01*
X1565151Y-208298D01*
X1564714Y-210922D01*
X1573884D01*
G01X1582869Y-211505D02*
X1590729Y-193422D01*
G01X1604299Y-210922D02*
Y-193422D01*
X1601679Y-196922D01*
G01Y-210922D02*
X1606919D01*
G01X1621799Y-193422D02*
X1620052Y-194005D01*
X1618742Y-195464D01*
X1617869Y-197213D01*
X1617214Y-199547D01*
X1616996Y-202172D01*
X1617214Y-204797D01*
X1617869Y-207131D01*
X1618742Y-208881D01*
X1620052Y-210339D01*
X1621799Y-210922D01*
X1623545Y-210339D01*
X1624856Y-208881D01*
X1625729Y-207131D01*
X1626384Y-204797D01*
X1626602Y-202172D01*
X1626384Y-199547D01*
X1625729Y-197213D01*
X1624856Y-195464D01*
X1623545Y-194005D01*
X1621799Y-193422D01*
G01X1635369Y-211505D02*
X1643229Y-193422D01*
G01X1652651Y-196339D02*
X1653961Y-194589D01*
X1655489Y-193714D01*
X1657236Y-193422D01*
X1659419Y-194005D01*
X1660947Y-195464D01*
X1661384Y-197213D01*
X1661166Y-198964D01*
X1660292Y-200422D01*
X1655926Y-203339D01*
X1653961Y-205380D01*
X1652651Y-208298D01*
X1652214Y-210922D01*
X1661384D01*
G01X1674299Y-193422D02*
X1672552Y-194005D01*
X1671242Y-195464D01*
X1670369Y-197213D01*
X1669714Y-199547D01*
X1669496Y-202172D01*
X1669714Y-204797D01*
X1670369Y-207131D01*
X1671242Y-208881D01*
X1672552Y-210339D01*
X1674299Y-210922D01*
X1676045Y-210339D01*
X1677356Y-208881D01*
X1678229Y-207131D01*
X1678884Y-204797D01*
X1679102Y-202172D01*
X1678884Y-199547D01*
X1678229Y-197213D01*
X1677356Y-195464D01*
X1676045Y-194005D01*
X1674299Y-193422D01*
G01X1691799Y-210922D02*
Y-193422D01*
X1689179Y-196922D01*
G01Y-210922D02*
X1694419D01*
G01X1708862D02*
X1709299Y-207131D01*
X1709954Y-203922D01*
X1710827Y-201005D01*
X1711919Y-197797D01*
X1713666Y-193422D01*
X1704932D01*
G01X1613155Y527165D02*
G03I-12800J0D01*
G01X1599496Y-165922D02*
Y-148422D01*
X1603862D01*
X1605609Y-149297D01*
X1606919Y-150464D01*
X1608011Y-152213D01*
X1608884Y-154256D01*
X1609102Y-157172D01*
X1608884Y-160089D01*
X1608011Y-162131D01*
X1606919Y-163881D01*
X1605609Y-165047D01*
X1603862Y-165922D01*
X1599496D01*
G01X1625729D02*
Y-154256D01*
G01Y-156297D02*
X1624856Y-155131D01*
X1623545Y-154547D01*
X1622017Y-154256D01*
X1620489Y-154839D01*
X1619179Y-156005D01*
X1618305Y-157755D01*
X1617869Y-160089D01*
X1618305Y-162422D01*
X1619179Y-164172D01*
X1620489Y-165339D01*
X1622017Y-165922D01*
X1623545Y-165630D01*
X1624856Y-164756D01*
X1625729Y-163589D01*
G01X1639299Y-148422D02*
Y-165922D01*
G01X1636242Y-154256D02*
X1642356D01*
G01X1653524Y-158047D02*
X1660511D01*
X1659856Y-156005D01*
X1658764Y-154839D01*
X1657236Y-154256D01*
X1655707Y-154547D01*
X1654397Y-155422D01*
X1653524Y-157464D01*
X1653087Y-159214D01*
Y-160964D01*
X1653524Y-162714D01*
X1654616Y-164464D01*
X1655926Y-165630D01*
X1657454Y-165922D01*
X1658982Y-165339D01*
X1660511Y-163589D01*
G54D35*
X24054Y21862D03*
X24143Y52374D03*
X19400Y562500D03*
X14700Y529100D03*
X138100Y208300D03*
X141900Y272900D03*
X138100Y241000D03*
X138800Y306100D03*
X140609Y337400D03*
X138410Y369674D03*
X786982Y368417D03*
X790099Y207600D03*
X793551Y240966D03*
X792787Y272898D03*
X790200Y336400D03*
X791970Y305000D03*
G54D227*
X1586547Y5502D03*
X1592453D03*
G54D146*
X722567Y397000D03*
X741433D03*
G54D128*
X652252Y335948D03*
X654221D03*
X656190D03*
X658159D03*
X660128D03*
X662097D03*
X664066D03*
X666035D03*
X668004D03*
X669973D03*
X671942D03*
X673911D03*
X675880D03*
X677849D03*
X679818D03*
X681787D03*
G54D155*
X1265488Y322910D03*
X1264182Y315862D03*
X1260234Y328907D03*
X1251491Y327228D03*
G54D164*
X1247619Y353586D03*
G54D137*
X708358Y63650D03*
X706390D03*
X704421D03*
X702453D03*
X700484D03*
X698516D03*
X696547D03*
X694579D03*
X692610D03*
X690642D03*
X708358Y549900D03*
X706390D03*
X704421D03*
X702453D03*
X700484D03*
X698516D03*
X696547D03*
X694579D03*
X692610D03*
X690642D03*
X1368558Y123600D03*
X1366590D03*
X1364621D03*
X1362653D03*
X1360684D03*
X1358716D03*
X1356747D03*
X1354779D03*
X1352810D03*
X1350842D03*
X1363358Y534200D03*
X1361390D03*
X1359421D03*
X1357453D03*
X1355484D03*
X1353516D03*
X1351547D03*
X1349579D03*
X1347610D03*
X1345642D03*
G54D245*
X1647186Y474076D03*
Y527817D03*
G54D182*
X1282412Y386838D03*
X1291431Y382075D03*
X1284195Y379437D03*
X1288657Y392100D03*
G54D236*
X1623812Y235469D03*
G54D53*
X18228Y178386D03*
X-1969D03*
X133563Y183126D03*
Y419626D03*
X783171Y183126D03*
Y419626D03*
X1454685Y338189D03*
X1600355Y527165D03*
G54D254*
X1699600Y235400D03*
Y454297D03*
X1866923Y235400D03*
X1955506Y454297D03*
G54D17*
X-14722Y452578D03*
X-5722D03*
X97600Y167800D03*
X88600D03*
X83820Y478080D03*
X74820D03*
X85865Y470975D03*
X76865D03*
X1683500Y82500D03*
X1692500D03*
X1883000Y554600D03*
X1890400D03*
X1883000Y557160D03*
X1890400D03*
X1883000Y552040D03*
X1890400D03*
G54D44*
X8141Y29503D03*
Y31275D03*
X8466Y60870D03*
Y62642D03*
Y64413D03*
Y66185D03*
Y67957D03*
Y69728D03*
Y71500D03*
Y73272D03*
Y75043D03*
Y76815D03*
X8141Y33046D03*
Y34818D03*
Y36590D03*
Y38361D03*
Y40133D03*
Y41905D03*
Y43676D03*
Y45448D03*
X-1959Y536159D03*
Y537931D03*
Y539702D03*
Y541474D03*
Y543246D03*
Y545017D03*
Y546789D03*
Y548561D03*
Y550332D03*
Y552104D03*
Y572159D03*
Y573931D03*
Y575702D03*
Y577474D03*
Y579246D03*
Y581017D03*
Y582789D03*
Y584561D03*
Y586332D03*
Y588104D03*
X122165Y216692D03*
Y248692D03*
Y250464D03*
Y252235D03*
Y254007D03*
Y255779D03*
Y257550D03*
Y259322D03*
Y261094D03*
Y262865D03*
Y264637D03*
Y218464D03*
Y220235D03*
Y222007D03*
Y223779D03*
Y225550D03*
Y227322D03*
Y229094D03*
Y230865D03*
Y232637D03*
Y280692D03*
Y282464D03*
Y284235D03*
Y286007D03*
Y287779D03*
Y289550D03*
Y291322D03*
Y293094D03*
Y294865D03*
Y296637D03*
Y312692D03*
Y314464D03*
Y316235D03*
Y318007D03*
Y319779D03*
Y321550D03*
Y323322D03*
Y325094D03*
Y326865D03*
Y328637D03*
Y344692D03*
Y346464D03*
Y348235D03*
Y350007D03*
Y351779D03*
Y353550D03*
Y355322D03*
Y357094D03*
Y358865D03*
Y360637D03*
Y376692D03*
Y378464D03*
Y380235D03*
Y382007D03*
Y383779D03*
Y385550D03*
Y387322D03*
Y389094D03*
Y390865D03*
Y392637D03*
X709959Y216526D03*
Y214754D03*
Y212983D03*
Y211211D03*
Y209439D03*
Y207668D03*
Y205896D03*
Y221841D03*
Y220069D03*
Y218298D03*
X771773Y216692D03*
Y218464D03*
Y220235D03*
Y222007D03*
Y223779D03*
Y225550D03*
Y227322D03*
Y229094D03*
Y230865D03*
Y232637D03*
Y248692D03*
Y250464D03*
Y252235D03*
Y254007D03*
Y255779D03*
Y257550D03*
Y259322D03*
Y261094D03*
Y262865D03*
Y264637D03*
Y312692D03*
Y314464D03*
Y316235D03*
Y318007D03*
Y319779D03*
Y321550D03*
Y323322D03*
Y325094D03*
Y326865D03*
Y328637D03*
Y280692D03*
Y282464D03*
Y284235D03*
Y286007D03*
Y287779D03*
Y289550D03*
Y291322D03*
Y293094D03*
Y294865D03*
Y296637D03*
Y344692D03*
Y346464D03*
Y348235D03*
Y350007D03*
Y351779D03*
Y353550D03*
Y355322D03*
Y357094D03*
Y358865D03*
Y360637D03*
X771723Y376692D03*
Y378464D03*
Y380235D03*
Y382007D03*
Y383779D03*
Y385550D03*
Y387322D03*
Y389094D03*
Y390865D03*
Y392637D03*
X1375048Y1017D03*
Y-755D03*
Y-2526D03*
Y-4298D03*
Y-6070D03*
Y-7841D03*
Y-9613D03*
Y-11385D03*
Y-13156D03*
Y-14928D03*
X1375359Y31269D03*
Y29498D03*
Y27726D03*
Y25954D03*
Y24183D03*
Y22411D03*
Y20639D03*
Y18868D03*
Y17096D03*
Y33041D03*
X1377666Y391909D03*
Y390137D03*
Y388366D03*
Y386594D03*
Y384822D03*
Y383051D03*
Y381279D03*
Y379507D03*
Y377736D03*
Y375964D03*
X1379359Y579897D03*
Y578125D03*
Y576354D03*
Y574582D03*
Y572810D03*
Y571039D03*
Y569267D03*
Y567495D03*
Y565724D03*
Y563952D03*
Y611097D03*
Y609325D03*
Y607554D03*
Y605782D03*
Y604010D03*
Y602239D03*
Y600467D03*
Y598695D03*
Y596924D03*
Y595152D03*
G54D290*
X1861735Y96422D03*
G54D62*
X35499Y431705D03*
X28499D03*
X28871Y441432D03*
X35871D03*
X28871Y448191D03*
X35871D03*
X47500Y562500D03*
X47150Y599650D03*
X68572Y18008D03*
X75572D03*
X68671Y10407D03*
X75671D03*
X61000Y216212D03*
X54000D03*
X104733Y514100D03*
Y589700D03*
Y551900D03*
X54500Y562500D03*
X54150Y599650D03*
X111733Y514100D03*
Y589700D03*
Y551900D03*
X378292Y13078D03*
X371292D03*
X378432Y51198D03*
X371432D03*
X378292Y589678D03*
X371292D03*
X378842Y551578D03*
X371842D03*
X647900Y286000D03*
X640900D03*
X718437Y-10548D03*
X725437D03*
X721131Y42955D03*
X721000Y520500D03*
X722606Y605050D03*
X715606D03*
X715370Y613530D03*
X722370D03*
X728131Y42955D03*
X753000Y512000D03*
X760000D03*
X728000Y520500D03*
X753343Y551878D03*
X760343D03*
X753343Y589678D03*
X760343D03*
X1028400Y13078D03*
X1021400D03*
X1028630Y51028D03*
X1021630D03*
X1028200Y551000D03*
X1021200D03*
X1027100Y589700D03*
X1020100D03*
X1338000Y46000D03*
X1331000D03*
X1508750Y547150D03*
X1501750D03*
X1559983Y567937D03*
X1552983D03*
X1585270Y558204D03*
Y565204D03*
X1592270Y558204D03*
Y565204D03*
X1691342Y495833D03*
X1698342D03*
X1771500Y516700D03*
X1785000Y100100D03*
X1778000D03*
X1796848Y160937D03*
X1803848D03*
X1778500Y516700D03*
X1837463Y144198D03*
X1844463D03*
X1955046Y76272D03*
X1955458Y88011D03*
X1962046Y76272D03*
X1962458Y88011D03*
G54D308*
X1949650Y220787D03*
Y228661D03*
G54D218*
X1481828Y599224D03*
X1517366Y600492D03*
G54D119*
X570000Y473000D03*
X598000D03*
X576900Y499100D03*
X604900D03*
X656800Y82000D03*
X654900Y103050D03*
X643500Y188500D03*
X649500Y239900D03*
X659000Y472700D03*
X684800Y82000D03*
X716500Y129500D03*
X672500Y129000D03*
X700500D03*
X682900Y103050D03*
X689000Y188300D03*
X717000D03*
X671500Y188500D03*
X677500Y239900D03*
X687000Y472700D03*
X744500Y129500D03*
X1224850Y500200D03*
X1252850D03*
X1337100Y554900D03*
X1309100D03*
X1568400Y552200D03*
X1540400D03*
X1800000Y505900D03*
X1828000D03*
G54D191*
X1442000Y-15000D03*
X1505000D03*
X1703503D03*
X1769504D03*
G54D317*
X1952756Y558464D03*
G54D173*
X1261528Y438443D03*
X1253007Y431370D03*
G54D272*
X1724041Y590805D03*
Y594742D03*
Y592773D03*
Y596711D03*
Y598679D03*
X1889300Y164242D03*
Y162273D03*
Y172116D03*
Y176053D03*
Y160305D03*
Y178021D03*
Y170147D03*
Y181958D03*
Y185895D03*
Y183927D03*
Y158336D03*
Y166210D03*
Y168179D03*
Y187864D03*
Y174084D03*
Y179990D03*
G54D80*
X63093Y202300D03*
X72936D03*
X82779D03*
X1628142Y240199D03*
Y263999D03*
X1892720Y525415D03*
X1914911Y495775D03*
X1934597D03*
X1924754D03*
X1900595Y525415D03*
X1908469D03*
X1916343D03*
X1924217D03*
X1922248Y518328D03*
X1912406D03*
X1904532D03*
G54D263*
X1724606Y235430D03*
X1930319Y451179D03*
G54D281*
X1895945Y-2322D03*
Y5670D03*
Y13662D03*
Y21654D03*
Y29646D03*
Y37638D03*
Y45630D03*
X1900945Y-6318D03*
Y1674D03*
Y9666D03*
Y17658D03*
Y25650D03*
Y33642D03*
Y41634D03*
Y49626D03*
G54D26*
X40500Y-42250D03*
Y-52250D03*
X10512Y467244D03*
X20512D03*
X30512D03*
X40512D03*
X60500Y-42250D03*
X80500D03*
X100500D03*
X60500Y-52250D03*
X80500D03*
X100500D03*
X50512Y467244D03*
X120500Y-42250D03*
X140500D03*
X120500Y-52250D03*
X140500D03*
X467246Y-52301D03*
Y-42301D03*
X487246Y-52301D03*
Y-42301D03*
X507246Y-52301D03*
Y-42301D03*
X527246Y-52301D03*
Y-42301D03*
X547246Y-52301D03*
Y-42301D03*
X567246Y-52301D03*
Y-42301D03*
X798984Y-52057D03*
Y-42057D03*
X818984Y-52057D03*
Y-42057D03*
X838984Y-52057D03*
Y-42057D03*
X858984Y-52057D03*
Y-42057D03*
X878984Y-52057D03*
Y-42057D03*
X898984Y-52057D03*
Y-42057D03*
X1135583Y-52285D03*
Y-42285D03*
X1155583Y-52285D03*
Y-42285D03*
X1392258Y-52257D03*
Y-42257D03*
X1412258Y-52257D03*
Y-42257D03*
X1432258Y-52257D03*
Y-42257D03*
X1452258Y-52257D03*
Y-42257D03*
X1884100Y493000D03*
X1894100D03*
X1891086Y612105D03*
Y602105D03*
G54D209*
X1510127Y79413D03*
Y160909D03*
G54D71*
X-6660Y499300D03*
X-11685Y495700D03*
X-11202Y516700D03*
X-6410Y546789D03*
X63261Y8225D03*
X72131Y348000D03*
X117589Y227500D03*
X117300Y259500D03*
X116442Y296473D03*
X117320Y291322D03*
X117352Y323322D03*
X110032Y373284D03*
X680330Y9287D03*
X714761Y210752D03*
X767277Y323658D03*
X1019589Y104065D03*
X1307363Y480350D03*
X1310700Y492569D03*
X1345561Y84900D03*
X1384906Y394845D03*
X1371874Y494665D03*
X1349779Y479400D03*
X1400050Y501950D03*
X1442800Y439175D03*
X1443000Y450275D03*
X1447800Y440125D03*
X1448000Y451225D03*
X1444550Y412364D03*
X1449350Y411414D03*
X1421608Y485300D03*
X1426993Y486250D03*
X1588510Y130663D03*
X1587477Y144569D03*
X1593420Y131800D03*
X1592816Y140550D03*
X1593401Y145489D03*
X1634358Y180527D03*
X1780543Y609000D03*
X1850407Y93219D03*
X1868541Y138200D03*
X1836531Y97664D03*
X1929336Y167130D03*
G54D282*
X1840675Y94600D03*
X1842250D03*
X1843825D03*
G54D138*
X703915Y98272D03*
X1772170Y136750D03*
Y132250D03*
Y127750D03*
Y123250D03*
Y150750D03*
Y146250D03*
Y141250D03*
X1730678Y604617D03*
X1746936Y603249D03*
X1806548Y155437D03*
X1780670Y141250D03*
Y136750D03*
Y132250D03*
Y127750D03*
Y123250D03*
Y150750D03*
Y146250D03*
G54D291*
X1893750Y130360D03*
Y128390D03*
Y120510D03*
Y114600D03*
Y112630D03*
Y126420D03*
Y118540D03*
Y116570D03*
Y124450D03*
Y122480D03*
G54D255*
X1670306Y231988D03*
X1676982Y227010D03*
X1902513Y197965D03*
G54D156*
X1256754Y321327D03*
X1261585Y307408D03*
X1261972Y300150D03*
X1245219Y322557D03*
X1260848Y293146D03*
G54D54*
X44291Y178386D03*
G54D129*
X662097Y301548D03*
X660128D03*
X658159D03*
X656190D03*
X654221D03*
X652252D03*
X681787D03*
X679818D03*
X677849D03*
X675880D03*
X673911D03*
X671942D03*
X669973D03*
X668004D03*
X666035D03*
X664066D03*
G54D246*
X1634611Y506852D03*
Y510789D03*
Y514726D03*
Y518663D03*
Y479293D03*
Y483230D03*
Y487167D03*
Y491104D03*
Y495041D03*
Y498978D03*
Y502915D03*
Y522600D03*
X1656611Y510789D03*
Y514726D03*
Y518663D03*
Y479293D03*
Y483230D03*
Y487167D03*
Y522600D03*
Y491104D03*
Y495041D03*
Y498978D03*
Y502915D03*
Y506852D03*
G54D165*
X1254441Y355073D03*
X1265918Y348135D03*
X1246918Y362262D03*
G54D192*
X1407422Y17283D03*
Y30669D03*
X1410571Y17283D03*
Y30669D03*
X1413721Y17283D03*
Y30669D03*
X1416871Y17283D03*
Y30669D03*
X1420020Y17283D03*
Y30669D03*
X1423170Y17283D03*
Y30669D03*
X1426319Y17283D03*
Y30669D03*
X1429469Y17283D03*
Y30669D03*
X1432619Y17283D03*
Y30669D03*
X1435768Y17283D03*
Y30669D03*
X1438918Y17283D03*
Y30669D03*
X1442067Y17283D03*
Y30669D03*
X1445217Y17283D03*
Y30669D03*
X1448367Y17283D03*
Y30669D03*
X1451516Y17283D03*
Y30669D03*
X1454666Y17283D03*
Y30669D03*
X1457815Y17283D03*
Y30669D03*
X1460965Y17283D03*
Y30669D03*
X1464115Y17283D03*
Y30669D03*
X1486162D03*
X1489311Y17283D03*
Y30669D03*
X1492461Y17283D03*
Y30669D03*
X1495611Y17283D03*
Y30669D03*
X1467264Y17283D03*
Y30669D03*
X1470414Y17283D03*
X1498760D03*
X1470414Y30669D03*
X1473563Y17283D03*
Y30669D03*
X1476713Y17283D03*
Y30669D03*
X1479863Y17283D03*
Y30669D03*
X1483012Y17283D03*
Y30669D03*
X1486162Y17283D03*
X1498760Y30669D03*
G54D228*
X1542009Y17268D03*
Y30668D03*
X1545159Y17268D03*
Y30668D03*
X1548309Y17268D03*
Y30668D03*
X1551459Y17268D03*
Y30668D03*
X1554609Y17268D03*
Y30668D03*
X1557759Y17268D03*
Y30668D03*
X1560909Y17268D03*
Y30668D03*
X1564059Y17268D03*
Y30668D03*
X1567209Y17268D03*
Y30668D03*
X1570359Y17268D03*
Y30668D03*
X1573509Y17268D03*
Y30668D03*
X1576659Y17268D03*
Y30668D03*
X1579809Y17268D03*
Y30668D03*
X1582959Y17268D03*
Y30668D03*
X1586109Y17268D03*
Y30668D03*
X1589259Y17268D03*
Y30668D03*
X1592409Y17268D03*
Y30668D03*
X1595559Y17268D03*
Y30668D03*
X1598709Y17268D03*
Y30668D03*
X1601859Y17268D03*
Y30668D03*
X1605009Y17268D03*
Y30668D03*
X1608159Y17268D03*
Y30668D03*
X1611309Y17268D03*
Y30668D03*
X1614459Y17268D03*
Y30668D03*
X1617609Y17268D03*
Y30668D03*
X1620759Y17268D03*
Y30668D03*
X1623909Y17268D03*
Y30668D03*
X1627059Y17268D03*
Y30668D03*
X1630209Y17268D03*
Y30668D03*
X1633359Y17268D03*
Y30668D03*
X1636509Y17268D03*
Y30668D03*
X1639659Y17268D03*
Y30668D03*
X1642809Y17268D03*
Y30668D03*
X1645959Y17268D03*
Y30668D03*
X1649109Y17268D03*
Y30668D03*
X1652259Y17268D03*
Y30668D03*
X1655409Y17268D03*
Y30668D03*
X1658559Y17268D03*
Y30668D03*
X1661709Y17268D03*
Y30668D03*
X1664859Y17268D03*
Y30668D03*
X1668009Y17268D03*
Y30668D03*
X1671159Y17268D03*
Y30668D03*
X1674309Y17268D03*
Y30668D03*
X1677459Y17268D03*
Y30668D03*
X1680609Y17268D03*
Y30668D03*
X1683759Y17268D03*
Y30668D03*
X1686909Y17268D03*
Y30668D03*
X1690059Y17268D03*
Y30668D03*
X1693209Y17268D03*
Y30668D03*
X1696359Y17268D03*
Y30668D03*
X1699509D03*
X1702659Y17268D03*
Y30668D03*
X1705809Y17268D03*
Y30668D03*
X1708959Y17268D03*
Y30668D03*
X1712109Y17268D03*
Y30668D03*
X1699509Y17268D03*
X1715259D03*
Y30668D03*
X1718409Y17268D03*
Y30668D03*
X1721559Y17268D03*
Y30668D03*
X1724709Y17268D03*
Y30668D03*
X1727859Y17268D03*
Y30668D03*
X1731009Y17268D03*
Y30668D03*
X1734159Y17268D03*
Y30668D03*
X1737309Y17268D03*
Y30668D03*
X1740459Y17268D03*
Y30668D03*
X1743609Y17268D03*
Y30668D03*
X1746759Y17268D03*
Y30668D03*
X1749909Y17268D03*
Y30668D03*
X1753059Y17268D03*
Y30668D03*
X1768807Y17268D03*
Y30668D03*
X1771957Y17268D03*
Y30668D03*
X1775107Y17268D03*
Y30668D03*
X1778257Y17268D03*
Y30668D03*
X1781407Y17268D03*
Y30668D03*
X1784557Y17268D03*
Y30668D03*
X1787707Y17268D03*
Y30668D03*
X1790857Y17268D03*
Y30668D03*
X1794007Y17268D03*
Y30668D03*
X1797157Y17268D03*
Y30668D03*
X1800307Y17268D03*
Y30668D03*
X1803457Y17268D03*
Y30668D03*
X1806607Y17268D03*
Y30668D03*
X1809757Y17268D03*
Y30668D03*
X1812907Y17268D03*
Y30668D03*
X1816057Y17268D03*
Y30668D03*
X1819207Y17268D03*
Y30668D03*
X1822357Y17268D03*
Y30668D03*
X1825507Y17268D03*
Y30668D03*
X1828657Y17268D03*
Y30668D03*
X1831807Y17268D03*
Y30668D03*
X1834957Y17268D03*
Y30668D03*
X1853857D03*
X1857007Y17268D03*
Y30668D03*
X1860157Y17268D03*
Y30668D03*
X1863307Y17268D03*
Y30668D03*
X1838107Y17268D03*
X1866457D03*
X1838107Y30668D03*
X1841257Y17268D03*
Y30668D03*
X1844407Y17268D03*
Y30668D03*
X1847557Y17268D03*
Y30668D03*
X1850707Y17268D03*
Y30668D03*
X1853857Y17268D03*
X1866457Y30668D03*
G54D18*
X-16362Y462160D03*
Y478340D03*
X-11242Y462160D03*
X-13802D03*
X-8682D03*
X-11242Y478340D03*
X-13802D03*
X-8682D03*
X1700080Y68600D03*
X1697520D03*
X1694960D03*
X1692400D03*
X1689840D03*
X1687280D03*
X1684720D03*
X1682160D03*
Y46400D03*
X1684720D03*
X1687280D03*
X1689840D03*
X1692400D03*
X1694960D03*
X1697520D03*
X1700080D03*
X1652160Y437500D03*
Y421320D03*
X1657280Y437500D03*
Y421320D03*
X1654720Y437500D03*
Y421320D03*
X1659840D03*
Y437500D03*
G54D183*
X1287176Y385127D03*
X1290105Y374700D03*
G54D45*
X19421Y27947D03*
X17649D03*
X15878D03*
X14106D03*
X12334D03*
X10563D03*
X19746Y59314D03*
X17974D03*
X16203D03*
X14431D03*
X12659D03*
X10888D03*
X9321Y534603D03*
X7549D03*
X5778D03*
X4006D03*
X2234D03*
X463D03*
X9321Y570603D03*
X7549D03*
X5778D03*
X4006D03*
X2234D03*
X463D03*
X133445Y215136D03*
X131673D03*
X129902D03*
X128130D03*
X126358D03*
X124587D03*
X133445Y279136D03*
X131673D03*
X129902D03*
X128130D03*
X126358D03*
X124587D03*
X133445Y247136D03*
X131673D03*
X129902D03*
X128130D03*
X126358D03*
X124587D03*
X133445Y311136D03*
X131673D03*
X129902D03*
X128130D03*
X126358D03*
X124587D03*
X133445Y343136D03*
X131673D03*
X129902D03*
X128130D03*
X126358D03*
X124587D03*
X133445Y375136D03*
X131673D03*
X129902D03*
X128130D03*
X126358D03*
X124587D03*
X698679Y223397D03*
X700451D03*
X702222D03*
X703994D03*
X705766D03*
X707537D03*
X783053Y215136D03*
X781281D03*
X779510D03*
X777738D03*
X775966D03*
X774195D03*
X783053Y247136D03*
X781281D03*
X779510D03*
X777738D03*
X775966D03*
X774195D03*
X783053Y279136D03*
X781281D03*
X779510D03*
X777738D03*
X775966D03*
X774195D03*
X783053Y311136D03*
X781281D03*
X779510D03*
X777738D03*
X775966D03*
X774195D03*
X783053Y343136D03*
X781281D03*
X779510D03*
X777738D03*
X775966D03*
X774195D03*
X783003Y375136D03*
X781231D03*
X779460D03*
X777688D03*
X775916D03*
X774145D03*
X1363768Y2573D03*
X1365540D03*
X1367311D03*
X1369083D03*
X1370855D03*
X1372626D03*
X1364079Y34597D03*
X1365851D03*
X1367622D03*
X1369394D03*
X1371166D03*
X1372937D03*
X1366386Y393465D03*
X1368158D03*
X1369929D03*
X1371701D03*
X1373473D03*
X1375244D03*
X1368079Y581453D03*
X1369851D03*
X1371622D03*
X1373394D03*
X1375166D03*
X1376937D03*
X1368079Y612653D03*
X1369851D03*
X1371622D03*
X1373394D03*
X1375166D03*
X1376937D03*
G54D81*
X72900Y168118D03*
X79900Y165559D03*
Y163000D03*
X72900D03*
X79900Y168118D03*
X104250Y327382D03*
X97250Y332500D03*
Y329941D03*
X104250Y332500D03*
X97250Y327382D03*
X652230Y485130D03*
Y487690D03*
X645230Y485130D03*
Y490250D03*
Y487690D03*
X652230Y490250D03*
X685268Y288147D03*
Y290706D03*
Y285588D03*
X678268D03*
Y288147D03*
Y290706D03*
X1446800Y368018D03*
X1453800Y362900D03*
Y365459D03*
X1446800Y362900D03*
X1453800Y368018D03*
X1528513Y322534D03*
X1521513Y325093D03*
Y327652D03*
X1528513D03*
X1521513Y322534D03*
X1646378Y202515D03*
Y205074D03*
X1639378Y202515D03*
Y207633D03*
Y205074D03*
X1646378Y207633D03*
X1649500Y329059D03*
Y326500D03*
Y323941D03*
Y318559D03*
Y313441D03*
X1656500Y323941D03*
Y329059D03*
Y316000D03*
Y318559D03*
Y313441D03*
X1737814Y576682D03*
Y571564D03*
X1730814D03*
Y574123D03*
Y576682D03*
X1828874Y-5980D03*
Y-8540D03*
X1835874Y-5980D03*
Y-11100D03*
Y-8540D03*
X1828874Y-11100D03*
X1793000Y130059D03*
X1800000Y127500D03*
X1793000Y124941D03*
X1800000Y130059D03*
Y124941D03*
X1788500Y620500D03*
X1795500D03*
X1788500Y617941D03*
X1795500Y615382D03*
X1788500D03*
X1795500Y617941D03*
X1911000Y546341D03*
Y548900D03*
Y543782D03*
X1904000D03*
Y546341D03*
Y548900D03*
G54D90*
X63382Y325500D03*
X65941D03*
X63382Y332500D03*
X68500D03*
X65941D03*
X68500Y325500D03*
X679430Y492970D03*
X681990D03*
X679430Y499970D03*
X684550D03*
X681990D03*
X684550Y492970D03*
X1510987Y325669D03*
X1508428Y318669D03*
X1505869D03*
Y325669D03*
X1510987Y318669D03*
X1581941Y326000D03*
X1584500Y333000D03*
X1587059Y326000D03*
X1581941Y333000D03*
X1587059D03*
X1634882Y217000D03*
X1640000D03*
Y224000D03*
X1637441D03*
X1634882D03*
X1699941Y77668D03*
X1702500Y84668D03*
X1705059Y77668D03*
X1699941Y84668D03*
X1705059D03*
X1763118Y58000D03*
X1760559Y51000D03*
X1758000Y58000D03*
X1763118Y51000D03*
X1758000D03*
X1798055Y143789D03*
X1795495D03*
X1798055Y136789D03*
X1792935D03*
X1795495D03*
X1792935Y143789D03*
X1801070Y115000D03*
X1798510D03*
X1801070Y108000D03*
X1795950D03*
X1798510D03*
X1795950Y115000D03*
X1836000Y539500D03*
Y546500D03*
X1876070Y552500D03*
X1873510D03*
X1876070Y545500D03*
X1870950D03*
X1873510D03*
X1870950Y552500D03*
X1841118Y546500D03*
X1838559Y539500D03*
X1841118D03*
X1925803Y578500D03*
X1928362Y585500D03*
X1930921Y578500D03*
X1925803Y585500D03*
X1930921D03*
G36*
G01X1956463Y209274D02*
G02X1954500Y205493I-1963J-1381D01*
G01X1950000D01*
G02X1947600Y207893I0J2400D01*
G01Y210293D01*
G02X1952400I2400J0D01*
G01X1954500D01*
G02X1954986Y210243I-1J-2400D01*
G03X1956463Y209274I1904J1292D01*
G37*
G54D237*
X1623812Y268699D03*
G54D147*
X721319Y496250D03*
X1394664Y544352D03*
X1541300Y316800D03*
X1634350Y204750D03*
X1736689Y173231D03*
X1732189D03*
X1727689D03*
X1723189D03*
Y165731D03*
X1727689D03*
X1732189D03*
X1736689D03*
X1718689D03*
Y173181D03*
X1714189Y165731D03*
X1855663Y145648D03*
G54D72*
X42724Y644684D03*
Y644656D03*
Y654684D03*
Y654656D03*
X67724Y644684D03*
Y644656D03*
Y654684D03*
Y654656D03*
X221656Y644656D03*
X196656D03*
X231446Y644756D03*
Y644784D03*
X221656Y644684D03*
X196656D03*
X221656Y654656D03*
X196656D03*
X231446Y654756D03*
Y654784D03*
X221656Y654684D03*
X196656D03*
X256446Y644756D03*
Y644784D03*
Y654756D03*
Y654784D03*
X409240Y644564D03*
X384240D03*
X418914Y644486D03*
Y644514D03*
X409240Y644536D03*
X384240D03*
X409240Y654564D03*
X384240D03*
X418914Y654486D03*
Y654514D03*
X409240Y654536D03*
X384240D03*
X443914Y644486D03*
Y644514D03*
Y654486D03*
Y654514D03*
X596707Y644293D03*
X571707D03*
X596708Y644266D03*
X571708D03*
X596707Y654293D03*
X571707D03*
X596708Y654266D03*
X571708D03*
X606462Y644245D03*
X631462D03*
X606462Y644217D03*
X631462D03*
X606462Y654245D03*
X631462D03*
X606462Y654217D03*
X631462D03*
X912351Y644245D03*
X887351D03*
X912351Y644273D03*
X887351D03*
X912351Y654245D03*
X887351D03*
X912351Y654273D03*
X887351D03*
X922116Y644206D03*
X947116D03*
X922116Y644234D03*
X947116D03*
X922116Y654206D03*
X947116D03*
X922116Y654234D03*
X947116D03*
X1200877Y644262D03*
Y644234D03*
Y654262D03*
Y654234D03*
X1225877Y644262D03*
X1235614Y644236D03*
X1260614D03*
X1235614Y644264D03*
X1260614D03*
X1225877Y644234D03*
Y654262D03*
X1235614Y654236D03*
X1260614D03*
X1235614Y654264D03*
X1260614D03*
X1225877Y654234D03*
X1514375Y644292D03*
Y644264D03*
Y654292D03*
Y654264D03*
X1539375Y644292D03*
Y644264D03*
Y654292D03*
Y654264D03*
G54D264*
X1724807Y451179D03*
X1841929Y235430D03*
X1851250Y584622D03*
Y576748D03*
Y568874D03*
G54D27*
X16117Y-43892D03*
X8543Y636173D03*
X1567200Y88000D03*
X1684907Y203562D03*
X1926693Y646063D03*
G54D174*
X1248059Y474441D03*
X1244243Y470374D03*
G54D219*
X1481729Y592414D03*
X1517267Y593682D03*
G54D63*
X-1950Y457450D03*
X-6550Y493850D03*
X85467Y302966D03*
X76500Y347900D03*
X84164Y380790D03*
X199221Y111179D03*
X317912Y108520D03*
X324046Y108154D03*
X353842Y114416D03*
X305817Y112075D03*
X313267Y115125D03*
X370193Y114952D03*
X361803Y113813D03*
X406851Y492615D03*
X418874Y498682D03*
X427596Y494704D03*
X419651Y492659D03*
X721921Y258921D03*
X718246Y258806D03*
X831125Y119452D03*
X829466Y109026D03*
X841741Y173258D03*
X832370Y160129D03*
X967478Y108478D03*
X972825Y107325D03*
X942425Y128074D03*
X955425Y112075D03*
X962875Y115125D03*
X951175Y122825D03*
X1019801Y114952D03*
X1011411Y113813D03*
X1004250Y115216D03*
X1248531Y115203D03*
X1370366Y72819D03*
X1587664Y138614D03*
X1563032Y106276D03*
X1576148Y115038D03*
X1540980Y350955D03*
X1648143Y177339D03*
X1610820Y223832D03*
X1678097Y164451D03*
X1863358Y138108D03*
G54D318*
X1901804Y557807D03*
Y576807D03*
X1919504Y557807D03*
Y576807D03*
X1901804Y594001D03*
Y613001D03*
X1919504Y594001D03*
Y613001D03*
G54D273*
X1727112Y600844D03*
X1733096D03*
X1891736Y190300D03*
X1895673D03*
X1893705D03*
X1897642D03*
X1901579D03*
X1913390D03*
X1915359D03*
X1921264D03*
X1907485D03*
X1909453D03*
X1903548D03*
X1905516D03*
X1911422D03*
X1919296D03*
X1917327D03*
X1899611D03*
G54D36*
X29654Y21862D03*
X29743Y52374D03*
X25000Y562500D03*
X20300Y529100D03*
X143700Y208300D03*
X147500Y272900D03*
X143700Y241000D03*
X144400Y306100D03*
X146209Y337400D03*
X144010Y369674D03*
X795699Y207600D03*
X799151Y240966D03*
X798387Y272898D03*
X795800Y336400D03*
X797570Y305000D03*
X792582Y368417D03*
G54D139*
X700515Y98272D03*
X1768770Y136750D03*
Y132250D03*
Y127750D03*
Y123250D03*
Y150750D03*
Y146250D03*
Y141250D03*
X1727278Y604617D03*
X1743536Y603249D03*
X1803148Y155437D03*
X1777270Y141250D03*
Y136750D03*
Y132250D03*
Y127750D03*
Y123250D03*
Y150750D03*
Y146250D03*
G54D283*
X1846100Y92325D03*
Y90750D03*
Y89175D03*
G54D64*
X28870Y503685D03*
X1377504Y62065D03*
X1776900Y86600D03*
G54D91*
X94973Y341879D03*
X98590Y371450D03*
X98540Y356360D03*
X98563Y348771D03*
X98520Y363880D03*
X96528Y387642D03*
X744020Y258770D03*
X750900Y264100D03*
X751700Y276900D03*
X745200Y270500D03*
X745400Y281900D03*
X1359512Y45934D03*
G54D157*
X1265720Y287844D03*
X1269395Y310026D03*
G54D193*
X1446179Y95353D03*
Y90353D03*
Y85353D03*
Y80353D03*
Y75353D03*
Y70353D03*
X1445232Y153080D03*
Y143080D03*
Y148080D03*
X1446179Y105353D03*
Y100353D03*
X1445232Y173080D03*
Y168080D03*
Y158080D03*
Y163080D03*
Y178080D03*
X1483779Y75353D03*
Y80353D03*
Y85353D03*
Y90353D03*
Y95353D03*
Y70353D03*
X1482832Y143080D03*
Y153080D03*
Y148080D03*
X1483779Y105353D03*
Y100353D03*
X1482832Y168080D03*
Y163080D03*
Y158080D03*
Y173080D03*
Y178080D03*
X1529699Y195920D03*
Y200920D03*
Y205920D03*
Y210920D03*
Y215920D03*
Y190920D03*
Y185920D03*
Y220920D03*
X1567299Y190920D03*
Y195920D03*
Y210920D03*
Y205920D03*
Y200920D03*
Y185920D03*
Y215920D03*
Y220920D03*
X1599200Y207000D03*
Y217000D03*
Y212000D03*
X1620800D03*
Y207000D03*
Y202000D03*
X1599200D03*
X1620800Y217000D03*
G54D37*
X45012Y-10625D03*
X43437D03*
X41862D03*
X40287D03*
X38713D03*
X37138D03*
X35563D03*
X33988D03*
X32413D03*
X46587D03*
G54D229*
X1569492Y125722D03*
X1692272Y119372D03*
X1682615Y113935D03*
G54D238*
X1632112Y252087D03*
Y256024D03*
Y259961D03*
X1615512Y242244D03*
Y246181D03*
Y250118D03*
Y254055D03*
Y257992D03*
X1632112Y244213D03*
Y248150D03*
X1615512Y261929D03*
G54D265*
X1766145Y460603D03*
X1769295Y441754D03*
Y460603D03*
X1772445Y441754D03*
Y460603D03*
X1734649Y441754D03*
Y460603D03*
X1737799Y441754D03*
Y460603D03*
X1740948Y441754D03*
Y460603D03*
X1744098Y441754D03*
Y460603D03*
X1747248Y441754D03*
Y460603D03*
X1750397Y441754D03*
Y460603D03*
X1753547Y441754D03*
Y460603D03*
X1756696Y441754D03*
Y460603D03*
X1759846Y441754D03*
Y460603D03*
X1762996Y441754D03*
Y460603D03*
X1766145Y441754D03*
X1775594D03*
Y460603D03*
X1778744Y441754D03*
Y460603D03*
X1781893Y441754D03*
Y460603D03*
X1785043Y441754D03*
Y460603D03*
X1788193Y441754D03*
Y460603D03*
X1791342Y441754D03*
Y460603D03*
X1794492Y441754D03*
Y460603D03*
X1797641Y441754D03*
Y460603D03*
X1800791Y441754D03*
Y460603D03*
X1803941Y441754D03*
Y460603D03*
X1807090Y441754D03*
Y460603D03*
X1810240Y441754D03*
Y460603D03*
X1813389Y441754D03*
Y460603D03*
X1816539Y441754D03*
Y460603D03*
X1819689Y441754D03*
Y460603D03*
X1822838Y441754D03*
Y460603D03*
X1825988Y441754D03*
Y460603D03*
X1829137Y441754D03*
Y460603D03*
X1832287Y441754D03*
Y460603D03*
X1835437Y441754D03*
Y460603D03*
X1838586Y441754D03*
Y460603D03*
X1841736Y441754D03*
Y460603D03*
X1844885Y441754D03*
Y460603D03*
X1848035Y441754D03*
Y460603D03*
X1851185Y441754D03*
Y460603D03*
X1854334Y441754D03*
Y460603D03*
X1857484Y441754D03*
Y460603D03*
X1860633Y441754D03*
Y460603D03*
X1863783Y441754D03*
Y460603D03*
X1866933Y441754D03*
Y460603D03*
X1870082Y441754D03*
Y460603D03*
X1873232Y441754D03*
Y460603D03*
X1876382Y441754D03*
Y460603D03*
X1879531Y441754D03*
Y460603D03*
X1882681Y441754D03*
Y460603D03*
X1885830Y441754D03*
Y460603D03*
X1888980Y441754D03*
Y460603D03*
X1892130Y441754D03*
Y460603D03*
X1895279Y441754D03*
Y460603D03*
X1907878D03*
X1911027Y441754D03*
Y460603D03*
X1914177Y441754D03*
Y460603D03*
X1917326Y441754D03*
Y460603D03*
X1920476Y441754D03*
X1898429D03*
Y460603D03*
X1901578Y441754D03*
Y460603D03*
X1904728Y441754D03*
Y460603D03*
X1907878Y441754D03*
X1920476Y460603D03*
G54D292*
X1869250Y112630D03*
Y124450D03*
Y130360D03*
Y114600D03*
Y116570D03*
Y128390D03*
Y126420D03*
Y120510D03*
Y118540D03*
Y122480D03*
G54D319*
X1970787Y139055D03*
Y196535D03*
G54D46*
X42600Y35244D03*
X42500Y62500D03*
X33500Y580000D03*
X33100Y544100D03*
X71100Y35244D03*
X71000Y62500D03*
X62000Y580000D03*
X61600Y544100D03*
X157624Y224533D03*
Y256533D03*
Y288533D03*
Y320533D03*
Y384533D03*
Y352033D03*
X186124Y224533D03*
Y256533D03*
Y288533D03*
Y320533D03*
Y384533D03*
Y352033D03*
X645684Y212995D03*
X674184D03*
X835732Y256533D03*
X807232D03*
X835732Y224533D03*
X807232D03*
X835732Y288533D03*
X807232D03*
X835732Y320533D03*
X807232D03*
X835732Y351533D03*
X807232D03*
X835687Y383681D03*
X807187D03*
X1313516Y22624D03*
X1342016D03*
X1314216Y-7476D03*
X1342716D03*
X1315000Y387500D03*
X1343500D03*
X1315400Y580556D03*
X1343900D03*
X1315300Y609456D03*
X1343800D03*
X1513700Y577066D03*
X1542200D03*
G54D256*
X1710594Y516950D03*
Y508850D03*
X1708626Y516950D03*
Y508850D03*
X1714530Y516950D03*
Y508850D03*
X1712562Y516950D03*
Y508850D03*
G54D247*
X1604323Y469147D03*
G54D166*
X1262771Y355220D03*
G36*
G01X24103Y622608D02*
G02Y598654I-10303J-11977D01*
G02X3767Y598425I-10304J11976D01*
G03X2702Y598731I-1068J-1710D01*
G01X-3D01*
G02X-11901Y610631I2J11900D01*
G02X-1Y622531I11901J-1D01*
G01X2709D01*
G03X3764Y622834I-1J1990D01*
G02X24103Y622608I10035J-12202D01*
G37*
G36*
G01X701268Y4104D02*
G02Y-19850I-10303J-11977D01*
G02X680932Y-20079I-10304J11976D01*
G03X679867Y-19773I-1068J-1710D01*
G01X677162D01*
G02X665264Y-7873I2J11900D01*
G02X677164Y4027I11901J-1D01*
G01X679874D01*
G03X680929Y4330I-1J1990D01*
G02X701268Y4104I10035J-12202D01*
G37*
G36*
G01Y622608D02*
G02Y598654I-10303J-11977D01*
G02X680932Y598425I-10304J11976D01*
G03X679867Y598731I-1068J-1710D01*
G01X677162D01*
G02X665264Y610631I2J11900D01*
G02X677164Y622531I11901J-1D01*
G01X679874D01*
G03X680929Y622834I-1J1990D01*
G02X701268Y622608I10035J-12202D01*
G37*
G36*
G01X1429615Y4104D02*
G02Y-19850I-10303J-11977D01*
G02X1409279Y-20079I-10304J11976D01*
G03X1408214Y-19773I-1068J-1710D01*
G01X1405509D01*
G02X1393611Y-7873I2J11900D01*
G02X1405511Y4027I11901J-1D01*
G01X1408221D01*
G03X1409276Y4330I-1J1990D01*
G02X1429615Y4104I10035J-12202D01*
G37*
G36*
G01Y622608D02*
G02Y598654I-10303J-11977D01*
G02X1409279Y598425I-10304J11976D01*
G03X1408214Y598731I-1068J-1710D01*
G01X1405509D01*
G02X1393611Y610631I2J11900D01*
G02X1405511Y622531I11901J-1D01*
G01X1408221D01*
G03X1409276Y622834I-1J1990D01*
G02X1429615Y622608I10035J-12202D01*
G37*
G36*
G01X1878434Y4104D02*
G02Y-19850I-10303J-11977D01*
G02X1858098Y-20079I-10304J11976D01*
G03X1857033Y-19773I-1068J-1710D01*
G01X1854328D01*
G02X1842430Y-7873I2J11900D01*
G02X1854330Y4027I11901J-1D01*
G01X1857040D01*
G03X1858095Y4330I-1J1990D01*
G02X1878434Y4104I10035J-12202D01*
G37*
G36*
G01Y622608D02*
G02Y598654I-10303J-11977D01*
G02X1858098Y598425I-10304J11976D01*
G03X1857033Y598731I-1068J-1710D01*
G01X1854328D01*
G02X1842430Y610631I2J11900D01*
G02X1854330Y622531I11901J-1D01*
G01X1857040D01*
G03X1858095Y622834I-1J1990D01*
G02X1878434Y622608I10035J-12202D01*
G37*
G54D148*
X721319Y492850D03*
X1394664Y540952D03*
X1541300Y313400D03*
X1634350Y201350D03*
X1736689Y169831D03*
X1732189D03*
X1727689D03*
X1723189D03*
Y162331D03*
X1727689D03*
X1732189D03*
X1736689D03*
X1718689D03*
Y169781D03*
X1714189Y162331D03*
X1855663Y142248D03*
G54D55*
X3937Y204370D03*
X-3937D03*
X-11811D03*
X35433D03*
X27559D03*
X19685D03*
X3937Y227992D03*
X-3937D03*
X-11811D03*
X35433D03*
X27559D03*
X19685D03*
X3937Y313504D03*
X-3937D03*
X-11811D03*
X3937Y337126D03*
X-3937D03*
X-11811D03*
X35433D03*
X27559D03*
X19685D03*
X35433Y313504D03*
X27559D03*
X19685D03*
X1527844Y80791D03*
G54D175*
X1239722Y474778D03*
X1232141Y467872D03*
G54D19*
X-17084Y467626D03*
X-16766Y500106D03*
X37739Y19501D03*
X13716Y24861D03*
X2934Y26933D03*
X23728Y18731D03*
X1382Y68100D03*
X1826Y56447D03*
X44310Y268160D03*
X33490Y267900D03*
X47100Y327000D03*
X-5680Y524570D03*
X10932Y523601D03*
X14700Y517000D03*
X-7360Y512000D03*
X-2083Y513704D03*
X-1000Y479000D03*
X5689Y481983D03*
X27280Y510420D03*
X-6200Y505400D03*
X-6566Y568363D03*
X-9291Y535201D03*
X54307Y-8051D03*
X62486Y-19184D03*
X51090Y8080D03*
X53382Y-1173D03*
X65384Y109750D03*
Y104750D03*
X65405Y118730D03*
X60831Y144750D03*
X65687Y132750D03*
X60831Y130750D03*
X60700Y116750D03*
X60801Y97750D03*
X60831Y139750D03*
X65687Y137750D03*
X60831Y125750D03*
X65405Y123730D03*
X60700Y111750D03*
X60801Y102750D03*
X91306Y157194D03*
X61356Y181000D03*
X61256Y186000D03*
X64187Y176332D03*
X104820Y195700D03*
X97800Y200800D03*
X86731Y189148D03*
X73500Y191500D03*
X97200Y265000D03*
X91600Y278700D03*
X62900Y339000D03*
X53250Y302800D03*
X48550Y301650D03*
X64700Y310525D03*
X84300Y305700D03*
Y310700D03*
X61625Y283201D03*
X72904Y284898D03*
X84300Y289000D03*
X82050Y283951D03*
X77103Y283900D03*
X84866Y294213D03*
X84300Y299000D03*
X58600Y302700D03*
X72600Y310800D03*
X77500Y312500D03*
X53025Y337475D03*
X93500Y285000D03*
X102040Y348960D03*
X101828Y371096D03*
X51923Y346164D03*
X60934Y362307D03*
X57395Y366795D03*
X55500Y371700D03*
X61914Y368731D03*
X60900Y348300D03*
X79100Y347000D03*
X49100Y354500D03*
X57800Y376100D03*
X60565Y380131D03*
X65000Y383000D03*
X74800Y379700D03*
X80200D03*
X62600Y375100D03*
X102160Y354780D03*
X101770Y363150D03*
X97472Y380934D03*
X71050Y478670D03*
X92326Y480398D03*
X141880Y-4651D03*
X109622Y128879D03*
X115536Y213508D03*
X154130Y190186D03*
X162788Y200650D03*
X162800Y195600D03*
X150000Y199850D03*
Y194850D03*
X115525Y245372D03*
X115536Y277508D03*
Y309508D03*
Y341508D03*
X118220Y360500D03*
X118629Y381193D03*
X109500Y370000D03*
X141880Y569340D03*
Y609749D03*
X178691Y-7260D03*
X206800Y246500D03*
X203947Y280933D03*
X206600Y372400D03*
X195233Y348402D03*
X215502Y531540D03*
X178691D03*
X173591Y534399D03*
X215502Y571949D03*
X178691D03*
Y607140D03*
X210402Y609999D03*
X247239Y-7050D03*
X284024Y-4401D03*
X284050Y30750D03*
X289124Y30540D03*
X252313Y68340D03*
X239778Y274478D03*
X247239Y531750D03*
X284024Y534399D03*
X252313Y569340D03*
X247213Y572199D03*
X289124Y571949D03*
X284050Y569550D03*
X284024Y609999D03*
X247213D03*
X331100Y-9786D03*
X311021Y-4536D03*
X347833Y-1743D03*
X326922Y497170D03*
X344486Y609864D03*
X364565Y-9786D03*
X414761Y-7108D03*
X361218Y-1858D03*
X364565Y35942D03*
X361642Y515200D03*
X361518Y510114D03*
X408069Y529007D03*
X364565Y574742D03*
Y566814D03*
X398029Y604499D03*
X361218Y604614D03*
X431494Y28007D03*
X438187Y-9786D03*
X424801D03*
X444880Y-4536D03*
X464732Y534399D03*
X469832Y531540D03*
X424801Y566807D03*
X464732Y572199D03*
X474998Y604499D03*
X444880Y604614D03*
X431494Y604499D03*
X464758Y607350D03*
X438187Y609864D03*
X501543Y33399D03*
X506643Y30540D03*
X538355Y-4401D03*
X538381Y569550D03*
X506644Y531540D03*
Y571949D03*
X501570Y569550D03*
X538381Y607350D03*
X506644Y609749D03*
X501570Y607350D03*
X528155Y610300D03*
X575166Y-4401D03*
X580266Y30540D03*
X579497Y202003D03*
X578980Y217884D03*
X575600Y259300D03*
X592300Y220500D03*
X580266Y534149D03*
X543455Y569340D03*
X575192Y569550D03*
X580266Y609749D03*
X543455D03*
X575192Y607350D03*
X564966Y610300D03*
X647000Y-12100D03*
X659747Y-12132D03*
X617400Y115800D03*
X605028Y119000D03*
X604977Y110200D03*
X606148Y229494D03*
X633410Y269610D03*
Y274610D03*
X656100Y275500D03*
X649800Y252600D03*
X652700Y270600D03*
X618279Y251393D03*
X637561Y317000D03*
X637600Y302000D03*
X632869Y293720D03*
X646520Y297400D03*
X657950Y296850D03*
X637681Y332390D03*
Y337390D03*
X659694Y351206D03*
X649194D03*
X620400Y463990D03*
X629600Y425100D03*
X622100Y417900D03*
X608800Y463475D03*
X609284Y480055D03*
X618800Y474500D03*
X619390Y469450D03*
X639120Y475620D03*
X608800Y468475D03*
Y473475D03*
X636500Y493924D03*
X627000Y478300D03*
X665396Y23000D03*
X680200Y13100D03*
X714300Y-1900D03*
X724837Y13852D03*
X701525Y35610D03*
X720572Y88700D03*
X713700Y224144D03*
X717420Y249920D03*
X679300Y261700D03*
X677800Y254100D03*
X667700Y275600D03*
X709949Y272647D03*
X706800Y278100D03*
X710700Y260200D03*
X723400Y250000D03*
X688924Y288147D03*
X668000Y298400D03*
X704404Y315875D03*
X673922Y298078D03*
X686140Y298260D03*
X667900Y339000D03*
X710272Y281911D03*
X724000Y291700D03*
X705800Y301600D03*
X697521Y325500D03*
X697352Y335500D03*
Y330500D03*
X697120Y300349D03*
X678730Y362841D03*
X686619Y392600D03*
X691240Y390039D03*
X669194Y351206D03*
X674194D03*
X679194D03*
X684194D03*
X676900Y381800D03*
X679385Y388705D03*
X687427Y384926D03*
X721894Y501346D03*
X675080Y485570D03*
X696000Y496800D03*
X679700Y489400D03*
X686200Y511700D03*
X680000Y511800D03*
X711704Y525483D03*
X707850Y505700D03*
X680029Y577503D03*
X718200Y581000D03*
X713132Y609306D03*
X765144Y213508D03*
X748700Y257500D03*
X759700Y232000D03*
X739500Y247500D03*
X749126Y220843D03*
X742897Y226773D03*
X739400Y253400D03*
X730000Y254675D03*
X754263Y254207D03*
X754846Y276340D03*
X765144Y245508D03*
X749090Y270250D03*
X765144Y277508D03*
X749800Y282300D03*
X757956Y328095D03*
X729405Y290725D03*
X743600Y304100D03*
X737750Y298894D03*
X737912Y315500D03*
X764980Y287980D03*
X765144Y309508D03*
Y341508D03*
X760500Y359800D03*
X767155Y385550D03*
X764159Y373743D03*
X763544Y522236D03*
X782567Y534700D03*
X773228Y528899D03*
X799620Y186547D03*
X798337Y181216D03*
X813700Y198900D03*
X804470Y186814D03*
X791488Y569340D03*
X836810Y572900D03*
X819378Y572500D03*
X810039Y528899D03*
X823199Y534399D03*
X828299Y531540D03*
X833464Y528899D03*
X791488Y607140D03*
X846850Y604499D03*
X823225Y607350D03*
X870275Y528899D03*
X860010Y534399D03*
X849810Y572500D03*
X860010Y572199D03*
X910432Y535100D03*
X901921Y534149D03*
X886621Y572500D03*
X901921Y569340D03*
X896821Y572199D03*
X865110Y607140D03*
X883661Y604499D03*
X901921Y607140D03*
X933632Y534399D03*
X943897Y528899D03*
X938732Y569340D03*
X933632Y572199D03*
X913779Y566699D03*
X917125Y572900D03*
X950590Y566699D03*
X933658Y607350D03*
X960629Y609864D03*
X987401Y509999D03*
X994094Y510114D03*
X1011250Y515200D03*
X1013873Y510114D03*
X1010826Y566814D03*
Y574742D03*
X984055Y607292D03*
X994094Y604614D03*
X1010826Y612242D03*
X1014173Y604614D03*
X1081102Y566807D03*
X1050983Y607292D03*
X1074409Y609864D03*
Y593642D03*
X1087795Y604614D03*
X1074409D03*
X1094488Y609864D03*
X1064369Y607292D03*
X1119440Y531540D03*
Y569340D03*
X1151178Y531750D03*
X1124606Y528899D03*
X1137992Y566699D03*
X1156252Y571949D03*
X1114340Y534399D03*
X1134645Y535100D03*
X1151152Y572199D03*
X1140952Y572500D03*
X1114340Y572199D03*
X1114366Y607350D03*
X1156252Y609749D03*
X1217476Y243482D03*
X1216234Y265555D03*
X1168110Y566699D03*
X1177763Y572500D03*
X1164763Y572900D03*
X1161417Y528899D03*
X1164763Y610700D03*
X1240000Y129500D03*
X1271500Y122500D03*
X1271490Y104700D03*
X1248616Y133817D03*
X1261800Y154973D03*
X1262569Y147201D03*
X1252000Y145300D03*
X1252437Y140192D03*
X1260737Y133877D03*
X1251980Y106960D03*
X1250200Y122900D03*
X1240010Y144754D03*
X1257800Y120800D03*
X1226785Y213003D03*
X1221300Y208000D03*
X1226500Y202400D03*
X1220580Y179810D03*
X1225908Y261800D03*
X1262900Y466504D03*
X1256320Y490660D03*
X1258126Y469540D03*
X1256350Y486080D03*
X1323000Y83000D03*
X1335120Y94450D03*
X1337400Y72000D03*
X1328500Y92500D03*
X1336900Y61600D03*
X1281799Y193190D03*
X1306585Y258250D03*
X1319888Y290205D03*
X1341375Y314675D03*
Y319675D03*
X1308887Y285015D03*
X1316600Y305500D03*
X1336336Y333825D03*
X1286831Y443058D03*
X1339900Y518900D03*
X1332600Y506300D03*
X1380219Y5581D03*
X1379025Y-9799D03*
X1362674Y46058D03*
X1348945Y40264D03*
X1370975Y67225D03*
X1343260Y53770D03*
X1351488Y74000D03*
X1358500Y74500D03*
X1347500Y83000D03*
X1357000Y86640D03*
X1383171Y57549D03*
X1379110Y45033D03*
X1392149Y68006D03*
X1371910Y48800D03*
X1370849Y59349D03*
X1380500Y50500D03*
X1372300Y86400D03*
X1363500Y77400D03*
X1403264Y82000D03*
X1345257Y100000D03*
X1348615Y96239D03*
X1353500Y96959D03*
X1345500Y107529D03*
X1364700Y96440D03*
X1373850Y120450D03*
X1392226Y319458D03*
X1349134Y317436D03*
X1400558Y320157D03*
X1380904Y319747D03*
X1371090Y319195D03*
X1360294Y318825D03*
X1396470Y330014D03*
X1381431Y284259D03*
X1383700Y392300D03*
X1388900Y387800D03*
X1380872Y378098D03*
X1402775Y457561D03*
X1388741Y493623D03*
X1383241Y498595D03*
X1368441Y492723D03*
X1362880Y497556D03*
X1360863Y481673D03*
X1347081Y507919D03*
X1390500Y539000D03*
X1383074Y581963D03*
X1398010Y590040D03*
X1465237Y11563D03*
X1460237D03*
X1446340D03*
X1441340D03*
X1407422Y13139D03*
X1455347Y92065D03*
X1457000Y82000D03*
X1452232Y109500D03*
X1456476Y278327D03*
X1443878Y268878D03*
X1453327Y278327D03*
X1450177Y275177D03*
X1447028Y272028D03*
X1453327Y275177D03*
Y268878D03*
X1447028D03*
X1450177Y272028D03*
X1456476D03*
Y275177D03*
X1450177Y268878D03*
X1453327Y272028D03*
X1456476Y268878D03*
X1459626Y272028D03*
Y278327D03*
Y275177D03*
Y268878D03*
X1462776Y272028D03*
Y275177D03*
Y278327D03*
Y268878D03*
X1447028Y278327D03*
X1443878Y275177D03*
Y278327D03*
Y272028D03*
X1447028Y275177D03*
X1450177Y278327D03*
X1413387Y320033D03*
X1456476Y306673D03*
X1453327Y303524D03*
X1462776Y294075D03*
Y290925D03*
X1453327Y281476D03*
X1462776Y297224D03*
Y287776D03*
X1443878Y316122D03*
X1459626Y284626D03*
X1456476Y281476D03*
X1447028Y312972D03*
X1450177Y309823D03*
X1453327Y306673D03*
X1456476Y303524D03*
X1459626Y300374D03*
X1462776Y284626D03*
Y281476D03*
X1459626D03*
X1453327Y294075D03*
X1459626Y290925D03*
X1443878Y297224D03*
X1447028Y294075D03*
X1450177D03*
X1443878D03*
Y290925D03*
X1450177D03*
X1456476Y294075D03*
X1453327Y290925D03*
X1447028D03*
X1443878Y287776D03*
X1456476Y290925D03*
X1459626Y287776D03*
X1450177D03*
X1447028D03*
X1453327D03*
X1456476Y284626D03*
X1443878D03*
X1450177D03*
X1456476Y287776D03*
X1453327Y284626D03*
X1447028D03*
X1443878Y281476D03*
X1450177D03*
X1447028D03*
X1443878Y312972D03*
X1447028Y309823D03*
X1450177Y306673D03*
X1443878D03*
Y309823D03*
X1447028Y306673D03*
Y303524D03*
X1450177D03*
X1453327Y300374D03*
X1459626Y297224D03*
X1443878Y303524D03*
X1447028Y300374D03*
X1456476Y297224D03*
X1453327D03*
X1450177Y300374D03*
X1443878D03*
X1456476D03*
X1459626Y294075D03*
X1447028Y297224D03*
X1450177D03*
Y312972D03*
X1447028Y316122D03*
X1453327Y309823D03*
X1456476Y312972D03*
X1453327Y316122D03*
X1456476Y309823D03*
X1450177Y316122D03*
X1453327Y312972D03*
X1456476Y316122D03*
X1459626Y312972D03*
Y306673D03*
X1462776Y303524D03*
X1459626Y309823D03*
Y316122D03*
Y303524D03*
X1462776Y306673D03*
Y312972D03*
Y309823D03*
Y300374D03*
Y316122D03*
X1456900Y387600D03*
X1457300Y373600D03*
X1420075Y378375D03*
Y393402D03*
Y383375D03*
Y388402D03*
X1413735Y396302D03*
Y391302D03*
X1414107Y447267D03*
X1461600Y449997D03*
X1464400Y454100D03*
X1461800Y465500D03*
X1454000D03*
X1410475Y453561D03*
X1456600Y454100D03*
X1464400Y459800D03*
X1456600D03*
X1448000Y431500D03*
X1431900Y453500D03*
X1447500Y448000D03*
X1431900Y442600D03*
X1448000Y437000D03*
X1431900Y448000D03*
X1447700Y442500D03*
X1431900Y437100D03*
X1464553Y508872D03*
X1436441Y489323D03*
X1412741Y494223D03*
X1436541Y494423D03*
X1436600Y482900D03*
X1413193Y482532D03*
X1436358Y525142D03*
X1451533Y527867D03*
X1413600Y531300D03*
X1432560Y561160D03*
X1428791Y535512D03*
X1419600Y531500D03*
X1453533Y532667D03*
X1426870Y530800D03*
X1423800Y534800D03*
X1421560Y563455D03*
X1415582Y562904D03*
X1439822Y537382D03*
X1428281Y546119D03*
X1429026Y541026D03*
X1410950Y589670D03*
X1493770Y6909D03*
X1484135Y11563D03*
X1488770Y6909D03*
X1479135Y11563D03*
X1513335Y92921D03*
X1499875Y90481D03*
X1513935Y104532D03*
Y116343D03*
X1524000Y123300D03*
X1490674Y98787D03*
X1498810Y108290D03*
X1526813Y108958D03*
X1526513Y115769D03*
X1500455Y114388D03*
X1496726Y120588D03*
X1473100Y128950D03*
X1514425Y137980D03*
X1526310Y142190D03*
X1485755Y131671D03*
X1500806Y133339D03*
X1526744Y98265D03*
X1483366Y115902D03*
X1498660Y102746D03*
X1520150Y127600D03*
X1502165Y251200D03*
X1505946Y254432D03*
X1478524Y278327D03*
X1491122Y268878D03*
X1487972D03*
X1481673Y278327D03*
X1484823Y275177D03*
X1487972Y272028D03*
X1484823D03*
X1478524D03*
X1481673Y275177D03*
X1465925Y272028D03*
Y275177D03*
Y268878D03*
Y278327D03*
X1469075D03*
Y268878D03*
Y275177D03*
Y272028D03*
X1472224Y268878D03*
Y278327D03*
Y275177D03*
Y272028D03*
X1475374Y268878D03*
Y275177D03*
Y278327D03*
X1481673Y272028D03*
X1484823Y268878D03*
X1475374Y272028D03*
X1478524Y268878D03*
Y275177D03*
X1481673Y268878D03*
X1487972Y278327D03*
X1491122Y275177D03*
X1487972D03*
X1491122Y272028D03*
Y278327D03*
X1484823D03*
X1498600Y334800D03*
X1481673Y281476D03*
X1472224Y290925D03*
Y294075D03*
X1481673Y303524D03*
X1478524Y306673D03*
X1469075Y297224D03*
X1465925D03*
Y287776D03*
X1469075D03*
X1472224Y297224D03*
Y287776D03*
X1491122Y316122D03*
X1475374Y284626D03*
X1478524Y281476D03*
X1487972Y312972D03*
X1484823Y309823D03*
X1481673Y306673D03*
X1478524Y303524D03*
X1475374Y300374D03*
X1465925Y294075D03*
X1469075D03*
X1465925Y290925D03*
X1469075D03*
X1465925Y284626D03*
X1469075D03*
X1465925Y281476D03*
X1469075D03*
X1472224Y284626D03*
X1475374Y281476D03*
X1472224D03*
X1481673Y294075D03*
X1478524Y290925D03*
X1491122Y297224D03*
X1487972Y294075D03*
X1484823D03*
X1491122D03*
Y290925D03*
X1484823D03*
X1475374Y294075D03*
X1481673Y290925D03*
X1487972D03*
X1491122Y287776D03*
X1475374Y290925D03*
X1478524Y284626D03*
X1484823Y287776D03*
X1487972D03*
X1481673D03*
X1478524D03*
X1491122Y284626D03*
X1484823D03*
X1475374Y287776D03*
X1481673Y284626D03*
X1487972D03*
X1491122Y281476D03*
X1484823D03*
X1487972D03*
Y309823D03*
X1491122Y312972D03*
X1484823Y306673D03*
X1487972Y303524D03*
X1491122Y309823D03*
X1487972Y306673D03*
X1491122D03*
X1484823Y303524D03*
X1481673Y300374D03*
X1478524Y297224D03*
X1491122Y303524D03*
X1487972Y300374D03*
X1478524D03*
X1481673Y297224D03*
X1484823Y300374D03*
X1491122D03*
X1475374Y297224D03*
X1478524Y294075D03*
X1487972Y297224D03*
X1484823D03*
X1472224Y306673D03*
Y303524D03*
Y309823D03*
Y312972D03*
Y300374D03*
X1475374Y306673D03*
Y316122D03*
Y309823D03*
X1481673Y312972D03*
X1484823Y316122D03*
X1475374Y312972D03*
X1478524Y316122D03*
Y309823D03*
Y312972D03*
X1484823D03*
X1487972Y316122D03*
X1481673D03*
Y309823D03*
X1465925Y303524D03*
Y312972D03*
Y306673D03*
X1469075Y303524D03*
X1465925Y309823D03*
Y316122D03*
Y300374D03*
X1469075Y306673D03*
Y316122D03*
Y309823D03*
Y300374D03*
X1475374Y303524D03*
X1469075Y312972D03*
X1472224Y316122D03*
X1517367Y349964D03*
X1484193Y371161D03*
X1481105D03*
X1475098Y381068D03*
X1487879Y368287D03*
X1477972Y374294D03*
Y377382D03*
X1467262Y420711D03*
X1508626Y503038D03*
X1506985Y510645D03*
X1510005Y518155D03*
X1498277Y508239D03*
X1490100Y520000D03*
X1485693Y508000D03*
X1479375Y507975D03*
X1503400Y524663D03*
X1484193Y493839D03*
X1481105D03*
X1475098Y483932D03*
X1487879Y496713D03*
X1477972Y487618D03*
Y490706D03*
X1472932Y619131D03*
X1504700Y611100D03*
X1518900Y619800D03*
X1508550Y619810D03*
X1513700Y619900D03*
X1478500Y619300D03*
X1571500Y-1406D03*
X1573048Y12506D03*
X1581998Y11355D03*
X1554148Y12306D03*
X1563498Y12506D03*
X1544698D03*
X1563200Y3400D03*
X1543500D03*
X1577269Y95344D03*
X1573121Y120649D03*
X1530101Y132671D03*
X1541765Y114000D03*
X1541831Y149030D03*
X1558042Y172448D03*
X1545802Y233529D03*
X1575645Y320664D03*
X1565244Y300934D03*
X1568524Y312885D03*
X1582800Y312100D03*
X1564400Y308383D03*
X1586500Y358400D03*
X1587684Y362653D03*
X1587032Y350996D03*
X1573895Y371161D03*
X1570807D03*
X1567121Y368287D03*
X1579902Y381068D03*
X1577028Y377382D03*
Y374294D03*
X1548300Y501500D03*
X1542475Y501900D03*
X1573895Y493839D03*
X1570807D03*
X1567121Y496713D03*
X1579902Y483932D03*
X1577028Y490706D03*
Y487618D03*
X1585155Y538574D03*
X1577000Y619500D03*
X1545407Y604713D03*
X1555600Y591100D03*
X1579680Y610279D03*
X1545407Y598393D03*
X1598602Y-600D03*
X1591848Y11406D03*
X1648748Y6325D03*
X1638865Y11105D03*
X1629148Y6825D03*
X1619798Y10755D03*
X1643865Y11105D03*
X1634148Y6825D03*
X1624798Y10755D03*
X1600898Y11355D03*
X1609833Y5425D03*
X1605898Y11355D03*
X1614833Y5425D03*
X1622635Y39900D03*
X1646848Y39462D03*
X1637398Y39862D03*
X1627715Y39934D03*
X1632006Y94500D03*
X1643500Y80400D03*
X1621100Y69600D03*
X1597987Y79500D03*
X1630826Y88087D03*
X1594452Y111377D03*
X1624764Y123365D03*
X1627914D03*
X1634213Y120215D03*
Y117066D03*
X1618465Y126514D03*
Y123365D03*
Y135963D03*
Y132814D03*
X1643662Y154861D03*
X1640512Y120215D03*
Y154861D03*
X1631064Y123365D03*
X1624764Y154861D03*
X1621615Y151711D03*
X1618465Y148562D03*
Y145412D03*
Y142262D03*
X1649961Y148562D03*
X1646812Y120215D03*
Y154861D03*
X1643662Y120215D03*
X1618465Y139113D03*
X1634213Y151711D03*
Y154861D03*
X1649961Y126514D03*
Y145412D03*
Y142262D03*
Y139113D03*
Y132814D03*
Y135963D03*
X1631064Y154861D03*
X1627914D03*
X1621615Y129664D03*
Y126514D03*
Y123365D03*
Y148562D03*
Y145412D03*
Y142262D03*
Y139113D03*
Y135963D03*
X1646812Y123365D03*
Y151711D03*
X1643662Y129664D03*
Y123365D03*
Y151711D03*
X1621615Y132814D03*
X1643662Y145412D03*
Y142262D03*
Y139113D03*
Y135963D03*
Y132814D03*
X1640512Y123365D03*
Y151711D03*
X1634213Y123365D03*
X1627914Y151711D03*
X1624764D03*
X1618465Y120215D03*
X1609016D03*
X1615316Y117066D03*
X1649961Y123365D03*
Y120215D03*
Y151711D03*
X1640512Y129664D03*
Y145412D03*
Y142262D03*
Y139113D03*
Y135963D03*
Y132814D03*
X1637363Y129664D03*
Y123365D03*
Y120215D03*
Y117066D03*
Y113916D03*
Y110766D03*
Y107617D03*
Y154861D03*
Y151711D03*
Y145412D03*
Y142262D03*
Y139113D03*
Y135963D03*
Y132814D03*
Y104467D03*
X1634213Y129664D03*
Y145412D03*
Y142262D03*
Y139113D03*
Y135963D03*
Y132814D03*
X1631064Y129664D03*
Y151711D03*
Y145412D03*
Y142262D03*
Y139113D03*
Y135963D03*
Y132814D03*
X1627914Y129664D03*
Y117066D03*
Y145412D03*
Y142262D03*
Y139113D03*
Y135963D03*
Y132814D03*
X1624764Y120215D03*
X1621615D03*
X1618465Y151711D03*
X1615316Y126514D03*
X1631064Y113916D03*
Y117066D03*
Y120215D03*
X1615316Y113916D03*
X1624764Y107617D03*
Y104467D03*
X1627914D03*
Y120215D03*
X1605867D03*
X1602717D03*
X1605867Y123365D03*
X1602717D03*
Y126514D03*
X1605867D03*
X1609016Y123365D03*
Y126514D03*
X1612166Y135963D03*
Y139113D03*
X1609016Y132814D03*
Y129664D03*
X1615316Y135963D03*
X1649961Y113916D03*
Y110766D03*
X1646812D03*
Y113916D03*
X1640512Y117066D03*
Y113916D03*
Y110766D03*
X1634213Y107617D03*
X1646812D03*
X1602717Y148562D03*
Y145412D03*
X1609016Y148562D03*
X1605867D03*
X1609016Y151711D03*
X1605867D03*
X1615316Y148562D03*
Y145412D03*
X1612166Y148562D03*
Y151711D03*
X1615316Y154861D03*
Y151711D03*
X1631064Y110766D03*
X1627914Y113916D03*
Y110766D03*
Y107617D03*
X1621615Y110766D03*
X1618465Y107617D03*
X1621615Y113916D03*
Y117066D03*
X1615316Y110766D03*
X1618465D03*
X1615316Y104467D03*
Y107617D03*
X1618465Y117066D03*
X1624764Y113916D03*
Y110766D03*
X1621615Y104467D03*
X1624764Y117066D03*
X1618465Y104467D03*
X1621615Y107617D03*
X1618465Y113916D03*
X1631064Y104467D03*
Y107617D03*
X1612166Y110766D03*
Y113916D03*
Y117066D03*
X1615316Y120215D03*
X1612166Y107617D03*
Y104467D03*
Y123365D03*
X1615316D03*
X1602717Y117066D03*
X1618465Y129664D03*
X1615316D03*
X1605867Y117066D03*
X1609016Y113916D03*
Y117066D03*
X1612166Y120215D03*
X1602717Y113916D03*
X1605867D03*
X1615316Y132814D03*
X1612166Y126514D03*
X1649961Y154861D03*
Y117066D03*
X1646812D03*
X1643662D03*
Y110766D03*
Y113916D03*
X1649961Y104467D03*
Y107617D03*
X1602717Y151711D03*
X1605867Y154861D03*
X1602717D03*
X1609016D03*
X1612166D03*
X1621615D03*
X1618465D03*
X1605867Y142262D03*
X1609016D03*
X1649961Y129664D03*
X1605867Y132814D03*
Y129664D03*
X1602717D03*
Y132814D03*
Y135963D03*
X1646812Y104467D03*
X1643662Y107617D03*
Y104467D03*
X1640512D03*
Y107617D03*
X1634213Y104467D03*
Y113916D03*
Y110766D03*
X1605867Y135963D03*
X1609016D03*
X1615316Y139113D03*
X1612166Y132814D03*
Y129664D03*
X1605867Y139113D03*
X1602717D03*
X1609016D03*
X1602717Y142262D03*
X1609016Y145412D03*
X1615316Y142262D03*
X1612166D03*
Y145412D03*
X1605867D03*
X1608056Y184771D03*
X1603300Y185100D03*
X1639258Y185620D03*
X1647852Y197374D03*
X1635621Y208259D03*
X1627914Y170609D03*
Y167459D03*
X1621615Y161160D03*
X1609016Y158010D03*
Y161160D03*
X1615316D03*
X1602717D03*
X1643662Y167459D03*
Y170609D03*
X1646812Y167459D03*
Y170609D03*
Y161160D03*
X1643662Y158010D03*
X1646812D03*
X1649961Y161160D03*
X1612166Y158010D03*
X1605867D03*
X1602717D03*
X1624764D03*
Y161160D03*
X1627914Y158010D03*
Y161160D03*
X1605867D03*
X1612166D03*
X1615316Y158010D03*
X1618465D03*
X1646812Y164310D03*
X1649961Y170609D03*
Y167459D03*
X1640512Y161160D03*
X1643662D03*
X1640512Y158010D03*
X1649961Y164310D03*
Y158010D03*
X1634213Y167459D03*
Y170609D03*
X1637363Y167459D03*
Y170609D03*
X1634213Y164310D03*
X1631064D03*
Y167459D03*
Y170609D03*
X1643662Y164310D03*
X1637363D03*
Y161160D03*
Y158010D03*
X1640512Y164310D03*
Y170609D03*
Y167459D03*
X1621615Y158010D03*
X1615316Y164310D03*
X1612166Y167459D03*
Y164310D03*
X1618465D03*
X1615316Y167459D03*
X1618465Y161160D03*
X1624764Y164310D03*
Y170609D03*
Y167459D03*
X1627914Y164310D03*
X1631064Y158010D03*
X1634213D03*
Y161160D03*
X1631064D03*
X1621615Y170609D03*
X1618465D03*
Y167459D03*
X1615316Y170609D03*
X1612166D03*
X1621615Y164310D03*
Y167459D03*
X1606849Y241210D03*
X1643775Y246137D03*
X1632128Y225472D03*
X1622000Y279495D03*
X1620159Y332004D03*
X1625400Y327667D03*
X1608764Y322440D03*
X1598878Y376346D03*
X1621800Y386300D03*
Y381500D03*
X1630800Y378500D03*
X1640266Y365500D03*
Y360500D03*
X1590154Y354762D03*
X1612250Y435500D03*
X1590037Y432515D03*
X1590581Y404170D03*
X1590580Y472370D03*
X1639113Y496734D03*
X1598700Y479225D03*
X1617771Y498714D03*
X1629530Y496374D03*
X1629500Y491500D03*
X1639271Y491135D03*
X1625094Y555200D03*
X1603919Y592750D03*
X1650869Y614200D03*
Y609200D03*
X1653748Y6325D03*
X1676428Y11381D03*
X1666979Y6236D03*
X1657369Y10258D03*
X1690948Y10725D03*
X1681428Y11381D03*
X1671979Y6236D03*
X1662373Y10154D03*
X1700200Y11317D03*
X1709771Y11261D03*
X1656298Y39462D03*
X1712308Y39350D03*
X1703073Y39679D03*
X1694098Y39462D03*
X1684648D03*
X1675198D03*
X1665748D03*
X1678400Y103000D03*
X1656260Y154861D03*
X1662560D03*
X1659410D03*
X1665709Y129664D03*
X1656260Y126514D03*
Y151711D03*
Y145412D03*
Y139113D03*
Y132814D03*
X1653111Y120215D03*
Y135963D03*
X1665709Y123365D03*
Y148562D03*
Y142262D03*
Y135963D03*
Y154861D03*
X1656260Y120215D03*
X1659410D03*
X1662560Y117066D03*
Y120215D03*
X1668859Y117066D03*
X1665709D03*
X1659410D03*
X1656260Y113916D03*
X1659410D03*
X1665709D03*
X1662560D03*
X1668859D03*
X1656260Y117066D03*
X1653111Y113916D03*
Y117066D03*
X1659410Y110766D03*
X1653111D03*
X1656260D03*
X1659410Y107617D03*
X1656260D03*
X1659410Y104467D03*
X1656260D03*
X1653111Y107617D03*
Y104467D03*
Y154861D03*
X1662560Y139113D03*
X1668859Y154861D03*
X1659410Y139113D03*
X1656260Y135963D03*
X1659410D03*
X1668859Y120215D03*
Y123365D03*
Y132814D03*
Y129664D03*
X1662560Y126514D03*
X1665709D03*
X1656260Y129664D03*
X1659410D03*
X1662560D03*
X1653111D03*
X1665709Y132814D03*
X1662560D03*
X1653111Y123365D03*
X1656260D03*
X1659410D03*
X1665709Y120215D03*
X1659410Y126514D03*
X1662560Y123365D03*
X1659410Y132814D03*
X1653111D03*
X1668859Y126514D03*
X1653111D03*
X1665709Y139113D03*
X1662560Y135963D03*
X1668859Y139113D03*
Y135963D03*
Y142262D03*
X1659410D03*
X1662560D03*
X1653111Y139113D03*
Y151711D03*
X1662560D03*
X1659410D03*
X1665709D03*
X1668859D03*
X1656260Y148562D03*
X1659410D03*
X1653111Y145412D03*
X1659410D03*
X1653111Y148562D03*
X1662560D03*
X1668859D03*
X1662560Y145412D03*
X1665709D03*
X1653111Y142262D03*
X1668859Y145412D03*
X1656260Y142262D03*
X1691439Y174354D03*
X1677600Y172700D03*
X1707100Y188300D03*
X1664390Y201163D03*
X1659643Y213505D03*
X1676924Y196731D03*
X1671688Y182925D03*
X1653111Y158010D03*
X1668859D03*
X1662560D03*
X1656260D03*
X1659410D03*
Y167459D03*
X1656260Y170609D03*
X1659410D03*
X1653111Y167459D03*
Y164310D03*
X1659410D03*
X1653111Y161160D03*
X1656260Y164310D03*
Y161160D03*
X1659410D03*
X1662560D03*
X1665709D03*
X1653111Y170609D03*
X1656260Y167459D03*
X1668859Y161160D03*
X1665709Y158010D03*
X1680769Y242605D03*
X1664762Y440735D03*
X1676041Y458884D03*
X1660834Y404934D03*
X1651754Y488025D03*
X1684650Y505200D03*
X1672159Y494042D03*
X1701617Y482706D03*
X1676800Y483800D03*
X1660680Y586750D03*
X1658369Y602250D03*
X1652499Y597950D03*
X1760693Y20045D03*
X1767069Y24010D03*
X1743152Y23197D03*
X1733168Y22312D03*
X1748152Y23197D03*
X1738168Y22312D03*
X1728678Y11381D03*
X1719297Y11180D03*
X1749085Y9177D03*
X1756895Y34252D03*
X1746550Y35925D03*
X1740598Y39486D03*
X1731183Y39465D03*
X1721758Y39880D03*
X1715100Y70500D03*
X1768886Y156173D03*
X1718591Y115876D03*
X1740638Y131624D03*
X1718591Y122175D03*
X1743787D03*
Y115876D03*
X1721740Y112726D03*
X1737488D03*
X1721740Y109577D03*
X1740638D03*
X1718591Y106427D03*
X1721740Y100128D03*
X1740638D03*
X1743787Y147372D03*
Y137923D03*
X1718591Y134774D03*
Y128474D03*
X1743787D03*
X1721740Y119026D03*
X1718591Y112726D03*
X1743787D03*
X1740638Y103278D03*
X1743787Y134774D03*
X1718591Y144222D03*
X1743787Y103278D03*
X1721740Y125325D03*
X1740638D03*
X1718591Y119026D03*
X1743787D03*
X1721740Y115876D03*
X1740638D03*
X1718591Y109577D03*
X1743787Y106427D03*
X1718591Y100128D03*
X1743787D03*
X1718591Y147372D03*
X1743787Y144222D03*
X1718591Y131624D03*
X1743787D03*
X1718591Y125325D03*
X1743787D03*
X1724890Y119026D03*
X1743787Y109577D03*
X1718591Y103278D03*
X1737488D03*
X1718591Y137923D03*
X1743787Y141073D03*
X1721740Y131624D03*
X1737488Y147372D03*
Y128474D03*
X1724890Y147372D03*
Y109577D03*
X1737488D03*
X1721740Y106427D03*
X1740638D03*
X1724890D03*
X1737488D03*
X1721740Y103278D03*
X1737488Y100128D03*
X1724890Y103278D03*
Y100128D03*
X1737488Y119026D03*
Y115876D03*
X1724890Y125325D03*
X1737488D03*
X1721740Y122175D03*
X1740638D03*
X1724890D03*
X1737488D03*
X1724890Y115876D03*
X1740638Y119026D03*
Y112726D03*
X1724890D03*
Y131624D03*
Y128474D03*
X1721740D03*
X1740638D03*
X1721740Y134774D03*
X1740638D03*
X1721740Y137923D03*
X1740638D03*
X1718591Y141073D03*
X1737488Y131624D03*
X1724890Y144222D03*
X1740638D03*
X1721740D03*
X1740638Y141073D03*
X1721740D03*
X1737488Y137923D03*
X1724890D03*
X1737488Y144222D03*
X1721740Y147372D03*
X1724890Y134774D03*
X1740638Y147372D03*
X1737488Y134774D03*
X1724890Y141073D03*
X1737488D03*
X1733484Y211631D03*
X1746125D03*
X1758725D03*
X1771325D03*
X1738484D03*
X1751125D03*
X1763725D03*
X1727193Y176525D03*
X1744792D03*
X1757390D03*
X1769988D03*
X1732193D03*
X1739792D03*
X1752390D03*
X1764988D03*
X1733563Y196776D03*
X1746082Y196843D03*
X1758668D03*
X1771241Y196841D03*
X1738563Y196776D03*
X1751082Y196843D03*
X1763668D03*
X1774451Y237712D03*
X1755554D03*
X1760554D03*
X1742398Y234681D03*
X1722251Y250532D03*
X1766077Y232681D03*
X1751900Y249700D03*
X1746900Y249804D03*
X1749462Y232955D03*
X1760767Y450408D03*
X1748169D03*
X1773366D03*
X1755767D03*
X1743169D03*
X1768366D03*
X1770325Y487355D03*
X1765325D03*
X1754300Y487855D03*
X1741900Y487755D03*
X1766700Y475655D03*
X1749300Y487855D03*
X1736900Y487755D03*
X1774300Y475055D03*
X1761700Y475655D03*
X1719560Y501770D03*
X1743000Y570000D03*
X1765300Y574700D03*
X1742381Y588530D03*
X1807127Y26918D03*
X1795078Y11900D03*
X1790078Y11860D03*
X1804462Y8830D03*
X1799462D03*
X1808100Y21800D03*
X1815150Y26650D03*
X1797700Y21018D03*
X1791500Y26918D03*
X1813795Y12165D03*
X1808795D03*
X1828874Y-13520D03*
X1819837Y21700D03*
X1786865Y22375D03*
X1829888Y10735D03*
X1808363Y40033D03*
X1803300Y39900D03*
X1817352Y36909D03*
X1812352Y36949D03*
X1797700Y36804D03*
X1792700Y36871D03*
X1794100Y70898D03*
X1807818Y124179D03*
X1827500Y144900D03*
X1809810Y155858D03*
X1790100Y154000D03*
X1776325Y211631D03*
X1777587Y176525D03*
X1783925Y211631D03*
X1796526Y212231D03*
X1809125D03*
X1821685Y212161D03*
X1788925Y211631D03*
X1801526Y212231D03*
X1814125D03*
X1826685Y212161D03*
X1790185Y176525D03*
X1802784D03*
X1815382D03*
X1782587D03*
X1795185D03*
X1807784D03*
X1820382D03*
X1783841Y196841D03*
X1776241D03*
X1814041D03*
X1801441D03*
X1809041D03*
X1821682D03*
X1796441D03*
X1788841D03*
X1807440Y165530D03*
X1836100Y179700D03*
X1807440Y169030D03*
Y162030D03*
X1826682Y196841D03*
X1817282Y250498D03*
X1798384D03*
X1779451Y237712D03*
X1793384Y250498D03*
X1812282D03*
X1785964Y450408D03*
X1780964D03*
X1836495Y450600D03*
X1823760Y450408D03*
X1811161D03*
X1798563D03*
X1831495Y450600D03*
X1818760Y450408D03*
X1806161D03*
X1793563D03*
X1824125Y488930D03*
X1811975Y488730D03*
X1801125Y488930D03*
X1789525D03*
X1819125D03*
X1806975Y488730D03*
X1796125Y488930D03*
X1784525D03*
X1829967Y476927D03*
X1817375Y478320D03*
X1794975Y479300D03*
X1779300Y475055D03*
X1825297Y476927D03*
X1812375Y478320D03*
X1789975Y479300D03*
X1801525Y473955D03*
X1806525D03*
X1784878Y496701D03*
X1825900Y523500D03*
X1832500Y539500D03*
X1788300Y585100D03*
X1791349Y589122D03*
X1832200Y567760D03*
X1831500Y544500D03*
X1831800Y552300D03*
X1809600Y582800D03*
X1793100Y578500D03*
X1816020Y571448D03*
X1812802Y578693D03*
X1829051Y591299D03*
X1822273Y595046D03*
X1788290Y612006D03*
X1877103Y60791D03*
X1838500Y40400D03*
X1856333Y34518D03*
X1894855Y142122D03*
X1893640Y147042D03*
X1888639D03*
X1887497Y105444D03*
X1881165Y105561D03*
X1886000Y156700D03*
X1885102Y101134D03*
X1876001Y105438D03*
X1861932Y146431D03*
X1869668Y146750D03*
X1848532Y144360D03*
X1897507Y124450D03*
X1886400Y178700D03*
X1883800Y210575D03*
X1854868Y184667D03*
X1836900Y165800D03*
X1889400Y191200D03*
X1896710Y194380D03*
X1847200Y202050D03*
X1840900Y179700D03*
X1845700D03*
X1858686Y180377D03*
X1885465Y166285D03*
X1855000Y167100D03*
X1864170Y211869D03*
X1892791Y200069D03*
X1884000Y188100D03*
X1865100Y174600D03*
X1846517Y253500D03*
X1854720Y253700D03*
X1841630Y454321D03*
X1863137Y452710D03*
X1867500Y447900D03*
X1837857Y468630D03*
X1842857D03*
X1868167Y467855D03*
X1863000Y480000D03*
X1859600Y476200D03*
X1876945Y471316D03*
X1877407Y479046D03*
X1855206Y471112D03*
X1837000Y534900D03*
X1839126Y583354D03*
X1847070Y537610D03*
X1914690Y152580D03*
X1929736Y128337D03*
X1899855Y142122D03*
X1909216Y142812D03*
X1908327Y149353D03*
X1923800Y151000D03*
X1916310Y149676D03*
X1919514Y131701D03*
X1943660Y98180D03*
X1940500Y157600D03*
X1925400Y196300D03*
X1909438Y204307D03*
X1929700Y163400D03*
X1940240Y169970D03*
X1931065Y175520D03*
X1927500Y170400D03*
X1929000Y158600D03*
X1939400Y198400D03*
X1929090Y193190D03*
X1933100Y436200D03*
X1959300Y518000D03*
X1957063Y474769D03*
X1948200Y474300D03*
X1900890Y477200D03*
X1918880Y586460D03*
X1961715Y555639D03*
X1962500Y578500D03*
X1961771Y591744D03*
X1963300Y612800D03*
G54D184*
X1401516Y23976D03*
X1392264D03*
X1504666Y29882D03*
X1513918Y23976D03*
G54D274*
X1736245Y594742D03*
Y598679D03*
Y596711D03*
Y592773D03*
Y590805D03*
X1923700Y176053D03*
Y178021D03*
Y187864D03*
Y183927D03*
Y181958D03*
Y179990D03*
Y185895D03*
Y170147D03*
Y172116D03*
Y174084D03*
Y166210D03*
Y168179D03*
Y162273D03*
Y160305D03*
Y158336D03*
Y164242D03*
G54D28*
G01X430749Y-124922D02*
G02I-12000J0D01*
G01X425599D02*
G02I-6850J0D01*
G01X434749D02*
X402749D01*
G01X434749Y-140922D02*
Y-220922D01*
G01D02*
X1729349D01*
G01X434749Y-176422D02*
X1729349D01*
G01X418749Y-140922D02*
Y-108922D01*
G01X434749Y-140922D02*
X1729349D01*
G01X941849D02*
Y-220922D01*
G01X1079349Y-140922D02*
Y-220922D01*
G01X1194349Y-140922D02*
Y-220922D01*
G01X1361849Y-140922D02*
Y-220922D01*
G01X1531849Y-140922D02*
Y-220922D01*
G01X1729349Y-140922D02*
Y-220922D01*
G01X1757349Y-124922D02*
G02I-12000J0D01*
G01X1752199D02*
G02I-6850J0D01*
G01X1745349Y-140922D02*
Y-108922D01*
G01X1761349Y-124922D02*
X1729349D01*
X39530Y5205D03*
X45670Y5185D03*
X33370D03*
X45429Y-4669D03*
X33628Y131D03*
X40994Y-7148D03*
X45700Y40D03*
X11539Y31427D03*
X27200Y30600D03*
X27239Y28027D03*
X25600Y32500D03*
X11600Y33944D03*
X11925Y74867D03*
X11864Y71294D03*
X11539Y39927D03*
X11500Y43400D03*
X11539Y47127D03*
X25886Y71467D03*
X25925Y75867D03*
X26185Y67017D03*
X27488Y64671D03*
X11925Y65311D03*
X27625Y73967D03*
X27525Y69367D03*
X11925Y67811D03*
X11864Y62794D03*
X24064Y61894D03*
X15111Y62553D03*
X27564Y61894D03*
X11600Y36444D03*
X25900Y40300D03*
X27564Y59394D03*
X24064D03*
X25700Y36200D03*
X27300Y34300D03*
Y38300D03*
X27208Y42313D03*
X27239Y47027D03*
X25700Y44400D03*
X27525Y77867D03*
X11864Y78494D03*
X13300Y509600D03*
X13600Y504300D03*
X4000Y509500D03*
X2485Y498185D03*
X13700Y498500D03*
X1439Y546583D03*
Y553783D03*
X1539Y550183D03*
X1500Y540600D03*
X15787Y551700D03*
X17100Y545400D03*
X13639Y534683D03*
Y537183D03*
X15800Y543300D03*
X15600Y539100D03*
X17139Y534683D03*
Y537183D03*
X17100Y541200D03*
X17035Y549558D03*
X15800Y547500D03*
X17139Y553683D03*
X1500Y543100D03*
X1439Y538083D03*
X15800Y579500D03*
Y575300D03*
X17108Y585513D03*
X17156Y581481D03*
X17100Y577400D03*
X17139Y573183D03*
X1500Y576600D03*
X17139Y570683D03*
X1500Y579100D03*
X1539Y586183D03*
X1439Y582583D03*
Y574083D03*
X15770Y587700D03*
X15800Y583500D03*
X1439Y589783D03*
X17139Y589683D03*
X95275Y217545D03*
X91626Y215364D03*
X85156Y212774D03*
X89386Y212744D03*
X87416Y215504D03*
X87542Y210043D03*
X83366Y215624D03*
X95140Y220946D03*
X91809Y221009D03*
X88447Y221136D03*
X85188Y221341D03*
X72074Y243282D03*
X65180Y243368D03*
X61800Y243400D03*
X68498Y243368D03*
X71500Y298000D03*
X66000Y292700D03*
X76800Y298000D03*
X76900Y292600D03*
X66500Y303400D03*
X76800D03*
X76500Y368300D03*
X76300Y358400D03*
X82037Y358542D03*
X70600Y368400D03*
X82100Y368300D03*
X70900Y358300D03*
X49560Y649770D03*
Y644670D03*
X54360D03*
X49560Y649570D03*
Y644670D03*
X54360D03*
X49560Y654670D03*
X54360D03*
X49560D03*
X54360D03*
X141263Y215216D03*
X125563Y218616D03*
X137763Y217716D03*
X128500Y218700D03*
X141263Y217716D03*
X137763Y215216D03*
X125624Y223633D03*
Y221133D03*
X141263Y234216D03*
X141200Y229600D03*
X141211Y225615D03*
X141300Y221700D03*
X139763Y231700D03*
Y227600D03*
Y223700D03*
X139582Y219800D03*
X125563Y234316D03*
X125663Y230716D03*
X125563Y227116D03*
X128200Y250700D03*
X125563Y250616D03*
X141263Y249716D03*
Y247216D03*
X137763D03*
Y249716D03*
X125624Y255633D03*
X125563Y259116D03*
X125663Y262716D03*
X125563Y266316D03*
X141300Y253700D03*
X139631Y251900D03*
X125624Y253133D03*
X137763Y279216D03*
X141263Y266216D03*
X139763Y255700D03*
Y259600D03*
X139800Y263700D03*
X141313Y257533D03*
X141263Y279216D03*
X141200Y261600D03*
X125624Y287633D03*
X125663Y294716D03*
X125563Y298316D03*
Y291116D03*
X128200Y282600D03*
X141263Y311216D03*
X137763D03*
X141263Y281716D03*
X139730Y284200D03*
X139763Y288200D03*
Y292000D03*
Y296000D03*
X125624Y285133D03*
X141200Y286100D03*
X141261Y290076D03*
X141300Y294000D03*
X141263Y298216D03*
X137763Y281716D03*
X125563Y282616D03*
X141211Y325515D03*
X128200Y314800D03*
X141263Y330216D03*
X139763Y327800D03*
X141300Y317500D03*
Y321500D03*
X139582Y315800D03*
X139763Y319400D03*
X125563Y323116D03*
X125663Y326716D03*
X125563Y330316D03*
Y314616D03*
X141263Y313716D03*
X137763D03*
X139763Y323600D03*
X125624Y317133D03*
Y319633D03*
X141289Y349488D03*
X128100Y346700D03*
X141300Y353300D03*
X141200Y357200D03*
X137763Y345716D03*
X141263D03*
Y343216D03*
X125624Y349133D03*
X137763Y343216D03*
X125563Y362316D03*
Y355116D03*
X125663Y358716D03*
X141263Y362216D03*
X139582Y347800D03*
X139763Y351400D03*
Y355200D03*
Y359500D03*
X125624Y351633D03*
X125563Y346616D03*
X141300Y381800D03*
X139763Y384000D03*
X125624Y381133D03*
X141263Y394216D03*
Y390416D03*
X141261Y385876D03*
X139736Y392300D03*
X125563Y378616D03*
X125663Y390716D03*
X125563Y387116D03*
Y394316D03*
X137763Y375216D03*
X141263D03*
Y377716D03*
X137763D03*
X139631Y379900D03*
X128500Y378700D03*
X139900Y388000D03*
X125624Y383633D03*
X214820Y649570D03*
Y644670D03*
X210020D03*
X214820Y649770D03*
Y644670D03*
X210020D03*
X214820Y654670D03*
X210020D03*
X214820D03*
X210020D03*
X238282Y649670D03*
Y644770D03*
X243082D03*
X238282Y649870D03*
Y644770D03*
X243082D03*
X238282Y654770D03*
X243082D03*
X238282D03*
X243082D03*
X354607Y277360D03*
Y273460D03*
Y269560D03*
Y328060D03*
Y324160D03*
Y320260D03*
Y316360D03*
Y312460D03*
Y308560D03*
Y304660D03*
Y300760D03*
Y296860D03*
Y292959D03*
Y289060D03*
Y285160D03*
Y281260D03*
X405306Y216909D03*
Y213009D03*
Y209109D03*
Y205210D03*
Y232509D03*
Y228610D03*
Y224709D03*
Y220809D03*
X357987Y267609D03*
X361367Y265660D03*
X364747Y263709D03*
X368127Y261760D03*
X371507Y259809D03*
X374887Y257860D03*
X378267Y255909D03*
X381647Y253960D03*
X388407D03*
X395166D03*
X401926D03*
X405306Y252009D03*
Y248109D03*
Y244209D03*
Y240309D03*
Y236409D03*
X378267Y341709D03*
X374887Y339760D03*
X371507Y337809D03*
X368127Y335860D03*
X364747Y333909D03*
X361367Y331960D03*
X357987Y330009D03*
X408686Y394359D03*
Y390460D03*
Y386560D03*
Y382660D03*
Y378760D03*
Y374860D03*
Y370959D03*
Y367060D03*
Y363160D03*
Y359260D03*
Y355360D03*
Y351460D03*
X405306Y349509D03*
X388407Y347560D03*
X395166D03*
X401926D03*
X385027Y345609D03*
X381647Y343660D03*
X402404Y649650D03*
Y644550D03*
X397604D03*
X402404Y649450D03*
Y644550D03*
X397604D03*
X402404Y654550D03*
X397604D03*
X402404D03*
X397604D03*
X425750Y649400D03*
Y644500D03*
X430550D03*
X425750Y649600D03*
Y644500D03*
X430550D03*
X425750Y654500D03*
X430550D03*
X425750D03*
X430550D03*
X589871Y649379D03*
Y644279D03*
X585071D03*
X589872Y649180D03*
Y644280D03*
X585072D03*
X589871Y654279D03*
X585071D03*
X589872Y654280D03*
X585072D03*
X659900Y256900D03*
Y269200D03*
X655900Y307700D03*
X656300Y312300D03*
X660700Y307700D03*
X655900Y316500D03*
X656000Y329800D03*
X655900Y320500D03*
X656000Y325100D03*
X660900Y329800D03*
X637143Y327000D03*
X613298Y649331D03*
Y644231D03*
X618098D03*
X613298Y649131D03*
Y644231D03*
X618098D03*
X613298Y654231D03*
X618098D03*
X613298D03*
X618098D03*
X692000Y45000D03*
Y48500D03*
X697500D03*
Y45000D03*
X692513Y213800D03*
X692673Y206200D03*
X692500Y210100D03*
X690861Y211917D03*
Y215717D03*
X692400Y218100D03*
X690861Y204317D03*
Y208117D03*
X706500Y217400D03*
Y214900D03*
Y207800D03*
X706561Y211417D03*
Y204217D03*
X694361Y223317D03*
Y220817D03*
X690861D03*
Y223317D03*
X672300Y269200D03*
X672200Y256800D03*
X706561Y219917D03*
X719900Y269300D03*
X725500Y279300D03*
X725300Y269400D03*
X719600Y279400D03*
X678200Y307800D03*
X672700Y307700D03*
X667100D03*
X678100Y324800D03*
X672200Y329800D03*
X678100Y329600D03*
X666900Y329700D03*
X678200Y313700D03*
Y319300D03*
X691900Y531350D03*
Y534850D03*
X697500Y534750D03*
Y531250D03*
X775171Y218616D03*
X787371Y215216D03*
Y217716D03*
X777700Y218600D03*
X731100Y269300D03*
Y279300D03*
X775200Y230500D03*
X775171Y227116D03*
Y234316D03*
X787371Y247216D03*
Y249716D03*
X775232Y221133D03*
X777700Y250600D03*
X775232Y223633D03*
X775171Y250616D03*
X775271Y262716D03*
X775171Y259116D03*
Y266316D03*
X775232Y253133D03*
Y255633D03*
X787371Y279216D03*
X775271Y294716D03*
X775171Y291116D03*
Y298316D03*
X777700Y282600D03*
X775232Y287633D03*
Y285133D03*
X775171Y282616D03*
X787371Y281716D03*
Y311216D03*
X775271Y326716D03*
X775171Y323116D03*
Y330316D03*
X777800Y314700D03*
X775171Y314616D03*
X787371Y313716D03*
X775232Y317133D03*
Y319633D03*
X775171Y346616D03*
Y362316D03*
X775271Y358716D03*
X775171Y355116D03*
X787371Y343216D03*
Y345716D03*
X775232Y349133D03*
X777600Y346600D03*
X775232Y351633D03*
X787321Y374916D03*
Y377316D03*
X775182Y383633D03*
Y381133D03*
X778000Y378700D03*
X775121Y378616D03*
Y394316D03*
X775221Y390716D03*
X775121Y387116D03*
X790871Y215216D03*
Y217716D03*
X789500Y231800D03*
X790900Y234000D03*
Y229700D03*
X790846Y225774D03*
X790882Y221723D03*
X790871Y247216D03*
Y249716D03*
X789471Y227742D03*
X789576Y223737D03*
X789554Y219723D03*
X790900Y253900D03*
X789432Y252000D03*
X790871Y266216D03*
X789432Y255800D03*
X790867Y257724D03*
X789432Y259800D03*
X789500Y263900D03*
X790885Y261711D03*
X790871Y279216D03*
Y311216D03*
X789432Y284200D03*
Y288300D03*
Y292400D03*
X789400Y296200D03*
X790871Y298216D03*
X790937Y294270D03*
X790900Y290300D03*
Y286200D03*
X790871Y281716D03*
Y313716D03*
X789432Y319900D03*
Y323900D03*
X790900Y322000D03*
Y326000D03*
X790871Y330216D03*
X789500Y328000D03*
X789478Y315671D03*
X790800Y317700D03*
X789432Y348100D03*
Y352100D03*
X789597Y356105D03*
X789500Y360200D03*
X790900Y358200D03*
X790835Y354048D03*
X790867Y350024D03*
X790871Y345716D03*
Y343216D03*
Y362216D03*
X790821Y374916D03*
X790900Y389300D03*
X789500Y391300D03*
X790900Y393400D03*
Y381100D03*
X789582Y383200D03*
X790900Y385300D03*
X789500Y387300D03*
X790821Y377316D03*
X789282Y379200D03*
X905515Y649159D03*
Y644259D03*
X900715D03*
X905515Y649359D03*
Y644259D03*
X900715D03*
X905515Y654259D03*
X900715D03*
X905515D03*
X900715D03*
X928952Y649120D03*
Y644220D03*
X933752D03*
X928952Y649320D03*
Y644220D03*
X933752D03*
X928952Y654220D03*
X933752D03*
X928952D03*
X933752D03*
X1004215Y277360D03*
Y273460D03*
Y269560D03*
X1007595Y267609D03*
X1010975Y265660D03*
X1014355Y263709D03*
X1017735Y261760D03*
X1021115Y259809D03*
X1024495Y257860D03*
X1027875Y255909D03*
X1031255Y253960D03*
X1027875Y341709D03*
X1024495Y339760D03*
X1021115Y337809D03*
X1017735Y335860D03*
X1014355Y333909D03*
X1010975Y331960D03*
X1007595Y330009D03*
X1004215Y328060D03*
Y324160D03*
Y320260D03*
Y316360D03*
Y312460D03*
Y308560D03*
Y304660D03*
Y300760D03*
Y296860D03*
Y292959D03*
Y289060D03*
Y285160D03*
Y281260D03*
X1031255Y343660D03*
X1054914Y216909D03*
Y213009D03*
Y209109D03*
Y205210D03*
Y232509D03*
Y228610D03*
Y224709D03*
Y220809D03*
X1038015Y253960D03*
X1044774D03*
X1051534D03*
X1054914Y252009D03*
Y248109D03*
Y244209D03*
Y240309D03*
Y236409D03*
X1058294Y394359D03*
Y390460D03*
Y386560D03*
Y382660D03*
Y378760D03*
Y374860D03*
Y370959D03*
Y367060D03*
Y363160D03*
Y359260D03*
Y355360D03*
Y351460D03*
X1054914Y349509D03*
X1038015Y347560D03*
X1044774D03*
X1051534D03*
X1034635Y345609D03*
X1219041Y649348D03*
Y644248D03*
X1214241D03*
X1219041Y649148D03*
Y644248D03*
X1214241D03*
X1219041Y654248D03*
X1214241D03*
X1219041D03*
X1214241D03*
X1242450Y649150D03*
Y644250D03*
X1247250D03*
X1242450Y649350D03*
Y644250D03*
X1247250D03*
X1242450Y654250D03*
X1247250D03*
X1242450D03*
X1247250D03*
X1355950Y-16507D03*
X1359450Y-7D03*
X1355950D03*
X1357489Y-1924D03*
X1359450Y2493D03*
X1355950D03*
X1357489Y-14424D03*
Y-10524D03*
Y-6124D03*
X1355889Y-8524D03*
X1355847Y-12275D03*
X1355989Y-3924D03*
X1356261Y32017D03*
X1356300Y20100D03*
X1356376Y24167D03*
X1356200Y28200D03*
X1357900Y30200D03*
X1357800Y26100D03*
X1357803Y22200D03*
X1356261Y15517D03*
X1357700Y17800D03*
X1359761Y32317D03*
X1371650Y-907D03*
X1371589Y-3424D03*
Y-5924D03*
X1371900Y28600D03*
X1371598Y-11633D03*
X1371632Y-9191D03*
X1371653Y-16654D03*
X1371605Y-14069D03*
X1371941Y22617D03*
X1371950Y20200D03*
X1371900Y17800D03*
Y15400D03*
Y26100D03*
Y31100D03*
X1350830Y60730D03*
X1356261Y34517D03*
X1356950Y54370D03*
X1356760Y66660D03*
X1357000Y60500D03*
X1359761Y34817D03*
X1350800Y66600D03*
X1351190Y54710D03*
X1363170Y54280D03*
X1362900Y60500D03*
X1363040Y66660D03*
X1352200Y104950D03*
Y108400D03*
X1357700D03*
Y104950D03*
X1391900Y232118D03*
X1386400Y237900D03*
X1403037Y302046D03*
X1358500Y374500D03*
X1360200Y377400D03*
X1358655Y379352D03*
X1362068Y393385D03*
X1360300Y381100D03*
X1360200Y384700D03*
Y389000D03*
X1358700Y386700D03*
X1358568Y390885D03*
Y393385D03*
X1358600Y382800D03*
X1362068Y390885D03*
X1374300Y377885D03*
Y381485D03*
X1374268Y374285D03*
Y389985D03*
X1374207Y384968D03*
Y387468D03*
X1391845Y348325D03*
X1352490Y515470D03*
X1346870Y515450D03*
X1352590Y519170D03*
X1346970Y519150D03*
X1360500Y570900D03*
Y574700D03*
X1360261Y578873D03*
X1360247Y567390D03*
X1360261Y562373D03*
Y581373D03*
X1362000Y576700D03*
Y572800D03*
X1362100Y569100D03*
X1362000Y565600D03*
X1375961Y569473D03*
X1376000Y565700D03*
X1375961Y562273D03*
X1363761Y581373D03*
X1375961Y577973D03*
X1376000Y575456D03*
Y572956D03*
X1390462Y541800D03*
X1400216Y560128D03*
X1363761Y612573D03*
X1360261D03*
X1360200Y597800D03*
X1361600Y599900D03*
X1361500Y595700D03*
X1360100Y610100D03*
X1360200Y606300D03*
Y602000D03*
X1361900Y608200D03*
X1361500Y604200D03*
X1360261Y593573D03*
X1375961Y600673D03*
X1375861Y597073D03*
X1375961Y593473D03*
X1363761Y610073D03*
X1375961Y609173D03*
X1375900Y604156D03*
Y606656D03*
X1413720Y301983D03*
X1418341Y494423D03*
Y477323D03*
X1442141Y477623D03*
X1442041Y489223D03*
X1409500Y538000D03*
X1420500Y549800D03*
X1420400Y538000D03*
X1475098Y374668D03*
Y377868D03*
X1478298Y371487D03*
X1481479Y368287D03*
X1484679D03*
X1507405Y518155D03*
X1498055Y516122D03*
X1509585Y510645D03*
X1500877Y508239D03*
X1492700Y520000D03*
X1475098Y487132D03*
Y490332D03*
X1481479Y496713D03*
X1484679D03*
X1478298Y493513D03*
X1527739Y644278D03*
D03*
X1472412Y596032D03*
Y599532D03*
X1479029Y596132D03*
X1477129Y597656D03*
X1474912Y596032D03*
X1480760Y611602D03*
X1485429Y597571D03*
X1491412Y596032D03*
X1489229Y597571D03*
X1487329Y596032D03*
X1512500Y598639D03*
X1510450Y597300D03*
X1507950D03*
X1510450Y600800D03*
X1508031Y599922D03*
X1524800Y598778D03*
X1522900Y597300D03*
X1526950D03*
X1518800Y597200D03*
X1520813Y598508D03*
X1516800Y598639D03*
X1514500Y597300D03*
X1527050Y613000D03*
X1523450Y612900D03*
X1519850Y613000D03*
X1487912Y611632D03*
X1491512Y611732D03*
X1484312D03*
X1511350Y613000D03*
X1513867Y612939D03*
X1516367D03*
X1475812Y611732D03*
X1474912Y599532D03*
X1478329Y611671D03*
X1483104Y596072D03*
X1481229Y597571D03*
X1527739Y654278D03*
D03*
X1589500Y-600D03*
X1547000Y263500D03*
Y269400D03*
X1541000Y263500D03*
Y269500D03*
X1544000Y266500D03*
X1579902Y377868D03*
Y374668D03*
X1573521Y368287D03*
X1570321D03*
X1576702Y371487D03*
X1542475Y509600D03*
X1548300Y511800D03*
X1579902Y490332D03*
Y487132D03*
X1570321Y496713D03*
X1573521D03*
X1576702Y493513D03*
X1589604Y585896D03*
X1581704D03*
X1532539Y649378D03*
Y644278D03*
Y649178D03*
Y644278D03*
X1581704Y590196D03*
X1589604D03*
X1558800Y599300D03*
X1560400Y611600D03*
X1564300Y599400D03*
X1564400Y605500D03*
X1561700Y602200D03*
X1552400Y607600D03*
X1554900Y607100D03*
X1556200Y602400D03*
X1554400Y599300D03*
X1564300Y611500D03*
X1532539Y654278D03*
D03*
X1635503Y340146D03*
X1629503D03*
Y346146D03*
X1635503Y346046D03*
X1632503Y343146D03*
X1594280Y472370D03*
X1709400Y513000D03*
X1713600D03*
X1727843Y597142D03*
X1732443Y592342D03*
Y597142D03*
X1727743Y592342D03*
X1788200Y93000D03*
Y89000D03*
Y85000D03*
X1820648Y155537D03*
X1816348D03*
Y163437D03*
X1818500Y159500D03*
X1820648Y163437D03*
X1860995Y84509D03*
X1856873Y91200D03*
X1856778Y87397D03*
X1864208Y87724D03*
X1864195Y84509D03*
X1864153Y91241D03*
X1860815Y91184D03*
X1842250Y90750D03*
X1887300Y121500D03*
X1850700Y156000D03*
X1875700Y115700D03*
Y121500D03*
X1881500Y115700D03*
Y121500D03*
Y127300D03*
X1887300D03*
X1875700D03*
X1887300Y115700D03*
X1846663Y153748D03*
X1854663Y158248D03*
X1846663D03*
X1885000Y227500D03*
X1918002Y98902D03*
X1934256Y99459D03*
X1913392Y149381D03*
X1900740Y178720D03*
X1900700Y172990D03*
Y167290D03*
X1906440Y178720D03*
X1906500Y173100D03*
X1906400Y167290D03*
X1912190Y178870D03*
X1912230Y167330D03*
Y173030D03*
X1909421Y208805D03*
X1903020Y225776D03*
G54D82*
X101200Y177500D03*
Y198500D03*
X746000Y202000D03*
Y223000D03*
G54D65*
X28870Y507085D03*
X1377504Y65465D03*
X1776900Y90000D03*
G54D92*
X94973Y338279D03*
X98590Y367850D03*
X98540Y352760D03*
X98563Y345171D03*
X98520Y360280D03*
X96528Y384042D03*
X744020Y255170D03*
X750900Y260500D03*
X745400Y278300D03*
X751700Y273300D03*
X745200Y266900D03*
X1359512Y42334D03*
G54D38*
X29850Y-8062D03*
Y-6487D03*
Y-4912D03*
Y-3337D03*
Y-1762D03*
Y-188D03*
Y1387D03*
Y2962D03*
Y4537D03*
Y6112D03*
G54D284*
X1838400Y92325D03*
Y89175D03*
Y90750D03*
G54D239*
X1613069Y302692D03*
G54D275*
X1808600Y48200D03*
Y73000D03*
X1786800Y48200D03*
Y73000D03*
G54D293*
X1880510Y133750D03*
X1886420D03*
X1884450D03*
X1882480D03*
X1876570D03*
X1874600D03*
X1872630D03*
X1878540D03*
X1890360D03*
X1888390D03*
G54D185*
X1360253Y214274D03*
X1371373Y211018D03*
G54D158*
X1253964Y297498D03*
X1254493Y290195D03*
X1237316Y312648D03*
G54D83*
X83000Y257700D03*
Y252700D03*
Y247700D03*
Y262700D03*
X83553Y234800D03*
Y229800D03*
Y224800D03*
Y239800D03*
G54D74*
X38500Y613000D03*
X136670Y159840D03*
X166595Y431153D03*
X572500Y105000D03*
X719000Y331200D03*
X796000Y103000D03*
X827000Y181000D03*
X828000Y417500D03*
X1440000Y513000D03*
X1573000Y576900D03*
G54D149*
X1241963Y132677D03*
X1233463Y128927D03*
Y136427D03*
X1574447Y291724D03*
X1565947Y287974D03*
Y295474D03*
X1650250Y217650D03*
Y225150D03*
X1658750Y221400D03*
G54D167*
X1270621Y355590D03*
G54D248*
X1611283Y567874D03*
Y615236D03*
X1658528Y567874D03*
X1705772D03*
Y615236D03*
G54D47*
X21100Y16000D03*
X22292Y503187D03*
X105712Y375972D03*
X398408Y106083D03*
X410543Y112617D03*
X396832Y114253D03*
X389148Y112345D03*
X404022Y112970D03*
X417190Y112652D03*
X383938Y103754D03*
X424817Y111219D03*
X422606Y116393D03*
X433172Y108790D03*
X439767Y105158D03*
X454520Y104627D03*
X481792Y112900D03*
X488242Y116350D03*
X697307Y275728D03*
X1033546Y103754D03*
X1048016Y106083D03*
X1060718Y112050D03*
X1074425Y111219D03*
X1045884Y114809D03*
X1081142Y110428D03*
X1090500Y104033D03*
X1038756Y112345D03*
X1053630Y112970D03*
X1066798Y112652D03*
X1104128Y104627D03*
X1101598Y110917D03*
X1131400Y112900D03*
X1109228Y123800D03*
X1118586Y143516D03*
X1138850Y115350D03*
X1134363Y143064D03*
X1141231Y139841D03*
X1535557Y350894D03*
X1657144Y241740D03*
X1661766Y235420D03*
X1850498Y87606D03*
X1882548Y174684D03*
X1903566Y146090D03*
G54D29*
X43586Y-19703D03*
G54D56*
X12290Y264640D03*
X18450Y267010D03*
X22970Y244400D03*
X28720Y244450D03*
X17120Y244220D03*
X24200Y267060D03*
X1969291Y486064D03*
Y497874D03*
G54D176*
X1225284Y468813D03*
X1234100Y475081D03*
G54D194*
X1432543Y291443D03*
G54D257*
X1712205Y536791D03*
X1707205D03*
X1702205D03*
X1697205D03*
X1692205D03*
X1687205D03*
X1712205D03*
X1707205D03*
X1702205D03*
X1697205D03*
X1692205D03*
X1687205D03*
X1717205D03*
D03*
G54D266*
X1770080Y504930D03*
X1788580D03*
G54D39*
X32413Y8675D03*
X33988D03*
X35563D03*
X37138D03*
X38713D03*
X40287D03*
X41862D03*
X43437D03*
X45012D03*
X46587D03*
G54D294*
X1888390Y109250D03*
X1874600D03*
X1882480D03*
X1880510D03*
X1890360D03*
X1872630D03*
X1876570D03*
X1878540D03*
X1884450D03*
X1886420D03*
G54D159*
X1236150Y300592D03*
G54D168*
X1279501Y350527D03*
G54D285*
X1843825Y86900D03*
X1842250D03*
X1840675D03*
G54D66*
X34126Y519000D03*
X47874D03*
X1393388Y86754D03*
X1395515Y405921D03*
X1381767D03*
X1407136Y86754D03*
G54D177*
X1316231Y205501D03*
X1303646Y199358D03*
X1293820Y221977D03*
G54D75*
X94683Y-5822D03*
Y31978D03*
Y13078D03*
Y69778D03*
Y50878D03*
Y88678D03*
Y514079D03*
Y532955D03*
Y570755D03*
Y589679D03*
Y551879D03*
Y608555D03*
X637793Y-5822D03*
Y31978D03*
Y13078D03*
Y69778D03*
Y50878D03*
Y88678D03*
Y514079D03*
Y532955D03*
Y570755D03*
Y589679D03*
Y551879D03*
Y608555D03*
X744293Y-5822D03*
Y31978D03*
Y13078D03*
Y69778D03*
Y88678D03*
Y50878D03*
Y514079D03*
Y570755D03*
Y532955D03*
Y589679D03*
Y551879D03*
Y608555D03*
X1287403Y-5822D03*
Y31978D03*
Y13078D03*
Y69778D03*
Y88678D03*
Y50878D03*
Y514079D03*
Y570755D03*
Y532955D03*
Y589679D03*
Y551879D03*
Y608555D03*
G54D57*
X3000Y280500D03*
X5560D03*
X8120D03*
X10680D03*
X3000Y290500D03*
X8120D03*
X5560D03*
X10680D03*
G54D258*
X1660158Y534035D03*
X1788110D03*
G54D267*
X1719500Y494500D03*
G54D84*
X67500Y255200D03*
X68053Y232300D03*
G54D195*
X1466693Y375787D03*
X1572599Y505315D03*
X1627642Y-14488D03*
X1647327Y-315D03*
G54D276*
X1835832Y56368D03*
X1859768D03*
G54D249*
X1629039Y580079D03*
X1626087Y585591D03*
X1629039Y565118D03*
X1626087Y570630D03*
X1637898Y580079D03*
X1634945Y585591D03*
X1637898Y565118D03*
X1634945Y570630D03*
X1643803D03*
X1646756Y565118D03*
Y580079D03*
X1643803Y585591D03*
X1640850Y582835D03*
X1631992D03*
X1623134D03*
X1640850Y567874D03*
X1631992D03*
X1623134D03*
X1646756Y610000D03*
Y595039D03*
X1643803Y600551D03*
Y615512D03*
X1629039Y610000D03*
X1626087Y615512D03*
X1629039Y595039D03*
X1626087Y600551D03*
X1637898Y610000D03*
X1634945Y615512D03*
X1637898Y595039D03*
X1634945Y600551D03*
X1623134Y612756D03*
X1640850Y597795D03*
X1631992D03*
X1623134D03*
X1640850Y612756D03*
X1631992D03*
X1676283Y580079D03*
X1673331Y585591D03*
X1676283Y565118D03*
X1673331Y570630D03*
X1685142Y580079D03*
X1682189Y585591D03*
X1685142Y565118D03*
X1682189Y570630D03*
X1691047D03*
X1694000Y565118D03*
Y580079D03*
X1691047Y585591D03*
X1688094Y582835D03*
X1679236D03*
X1670378D03*
X1688094Y567874D03*
X1679236D03*
X1670378D03*
X1694000Y595039D03*
X1691047Y600551D03*
Y615512D03*
X1676283Y610000D03*
X1673331Y615512D03*
X1676283Y595039D03*
X1673331Y600551D03*
X1685142Y610000D03*
X1682189Y615512D03*
X1685142Y595039D03*
X1682189Y600551D03*
X1688094Y612756D03*
X1679236D03*
X1670378D03*
X1688094Y597795D03*
X1679236D03*
X1670378D03*
G54D93*
X78395Y288750D03*
X76425D03*
X74455D03*
X72485D03*
X70515D03*
X68545D03*
X66575D03*
X64605D03*
G54D48*
X24582Y-3053D03*
X225718Y130200D03*
X222829Y141300D03*
X210896Y140300D03*
X213828Y134900D03*
X195800Y124600D03*
X200900Y120704D03*
X231492Y140500D03*
X239892Y135000D03*
X242592Y142000D03*
X267186Y141000D03*
X270504Y136000D03*
X234192Y134000D03*
X256492Y130000D03*
X259149Y140500D03*
X249872Y141500D03*
X252612Y135500D03*
X245292Y125500D03*
X251642Y123500D03*
X331592Y114748D03*
X335792Y104069D03*
X333692Y110190D03*
X329573Y107022D03*
X324692Y114882D03*
X353714Y103936D03*
X349692Y108643D03*
X347592Y103993D03*
X345492Y112063D03*
X337892Y113956D03*
X329730Y489798D03*
X384377Y114881D03*
X378422Y106505D03*
X375287Y127696D03*
X360617Y103689D03*
X377272Y116996D03*
X363186Y108014D03*
X374137Y140732D03*
X382392Y109922D03*
X405733Y104472D03*
X412792Y104540D03*
X377149Y462175D03*
X380350Y453103D03*
X372781Y491333D03*
X377192Y498249D03*
X403192Y498191D03*
X419092Y104695D03*
X474326Y112500D03*
X466112Y114000D03*
X460292Y115000D03*
X467262Y109000D03*
X425492Y104752D03*
X481691Y104000D03*
X496902Y116000D03*
X516442Y130500D03*
X521052Y117000D03*
X508892Y122500D03*
X511492Y133000D03*
X533203Y119500D03*
X524392Y132500D03*
X526911Y125000D03*
X537511Y135500D03*
X557692Y133500D03*
X560211Y140500D03*
X547328Y120500D03*
X555147Y139000D03*
X540992Y141000D03*
X543659Y126500D03*
X544809Y135000D03*
X660128Y296830D03*
X699300Y36012D03*
X726287Y258979D03*
X847304Y138000D03*
X861026Y141000D03*
X858337Y125500D03*
X850036Y128500D03*
X889500Y135000D03*
X892200Y142000D03*
X881100Y140500D03*
X883800Y134000D03*
X906100Y130000D03*
X908757Y140500D03*
X899480Y141500D03*
X902220Y135500D03*
X894900Y125500D03*
X901250Y123500D03*
X916794Y141000D03*
X920112Y136000D03*
X945300Y140000D03*
X948000Y130500D03*
X936900Y135000D03*
X926300Y142500D03*
X929100Y137500D03*
X981200Y115148D03*
X985400Y104069D03*
X1033985Y115181D03*
X983300Y110390D03*
X979181Y107022D03*
X974300Y115182D03*
X1028030Y115156D03*
X1024895Y111035D03*
X1010225Y103689D03*
X1026880Y103936D03*
X1012794Y108014D03*
X1032000Y110422D03*
X1003322Y103936D03*
X999300Y108743D03*
X997200Y103793D03*
X995100Y112669D03*
X987500Y113956D03*
X1003580Y138417D03*
X1026757Y461106D03*
X1029958Y451876D03*
X979338Y490843D03*
X1022389Y490150D03*
X1026800Y497824D03*
X1081732Y104117D03*
X1068700Y104697D03*
X1055341Y104472D03*
X1062400Y104568D03*
X1075100Y104812D03*
X1055670Y464870D03*
X1052800Y498443D03*
X1051700Y476126D03*
X1059640Y474572D03*
X1047730Y470954D03*
X1131299Y104000D03*
X1119700Y116492D03*
X1123934Y112500D03*
X1109900Y115000D03*
X1116870Y109000D03*
X1146510Y115200D03*
X1166050Y130500D03*
X1170660Y117000D03*
X1158500Y122500D03*
X1161100Y133000D03*
X1182811Y119500D03*
X1207300Y133500D03*
X1209819Y140500D03*
X1174000Y132500D03*
X1176519Y125000D03*
X1196936Y120500D03*
X1204755Y139000D03*
X1190600Y141000D03*
X1193267Y126500D03*
X1187119Y135500D03*
X1194417Y135000D03*
X1202961Y464997D03*
X1190650Y466472D03*
X1194970Y474489D03*
X1359657Y96096D03*
X1357000Y96213D03*
X1354309Y505157D03*
X1349000Y505800D03*
X1557500Y350500D03*
X1552400D03*
X1547300Y350658D03*
X1563712Y590349D03*
X1620827Y95153D03*
X1624188Y96700D03*
X1634977Y96860D03*
X1615749Y96720D03*
X1590991Y202378D03*
X1658500Y179742D03*
X1874600Y140762D03*
G54D186*
X1382500Y381270D03*
X1437930Y459805D03*
X1429229Y548455D03*
X1602520Y425800D03*
X1597400Y424761D03*
G54D76*
X49150Y6112D03*
Y4537D03*
Y2962D03*
Y1387D03*
Y-188D03*
Y-1762D03*
Y-3337D03*
Y-4912D03*
Y-6487D03*
Y-8062D03*
G54D67*
X17750Y510887D03*
Y509312D03*
Y507737D03*
Y506162D03*
Y504587D03*
Y503013D03*
Y501438D03*
Y499863D03*
Y498288D03*
Y496713D03*
X675750Y270087D03*
Y268512D03*
Y266937D03*
Y265362D03*
Y263787D03*
Y262213D03*
Y260638D03*
Y259063D03*
Y257488D03*
Y255913D03*
X1366650Y67587D03*
Y66012D03*
Y64437D03*
Y62862D03*
Y61287D03*
Y59713D03*
Y58138D03*
Y56563D03*
Y54988D03*
Y53413D03*
G54D268*
X1719500Y499620D03*
G54D196*
X1446500Y382000D03*
Y394000D03*
G54D178*
X1296586Y198653D03*
X1286850Y207463D03*
G54D277*
X1836693Y120158D03*
X1954804D03*
G54D49*
X2940Y41740D03*
Y47240D03*
X116124Y112393D03*
Y106893D03*
X194600Y242848D03*
Y248348D03*
Y238348D03*
Y232848D03*
Y274000D03*
Y279500D03*
Y303000D03*
Y308500D03*
Y335730D03*
Y341230D03*
Y363600D03*
Y369100D03*
X411989Y274654D03*
Y269154D03*
X416889Y274654D03*
Y269154D03*
X407089Y274654D03*
Y269154D03*
X402148Y274841D03*
Y269341D03*
X397256Y274841D03*
Y269341D03*
X411060Y300154D03*
Y305654D03*
X415960Y300154D03*
Y305654D03*
X410860Y283000D03*
Y288500D03*
X415860Y283000D03*
Y288500D03*
X406160Y300154D03*
Y305654D03*
Y283154D03*
Y288654D03*
X416192Y318900D03*
Y313400D03*
X412407Y328713D03*
Y334213D03*
X417307Y328713D03*
Y334213D03*
X407507Y328713D03*
Y334213D03*
X406192Y318900D03*
Y313400D03*
X367360Y315654D03*
Y321154D03*
X372060Y315654D03*
Y321154D03*
X376760Y315654D03*
Y321154D03*
X382413Y324585D03*
Y330085D03*
X387892Y328000D03*
Y333500D03*
X402592Y328200D03*
Y333700D03*
X397692Y328200D03*
Y333700D03*
X392792Y328200D03*
Y333700D03*
X391492Y318900D03*
Y313400D03*
X386592Y318900D03*
Y313400D03*
X401292Y318900D03*
Y313400D03*
X396392Y318900D03*
Y313400D03*
X381692Y318900D03*
Y313400D03*
X391460Y300154D03*
Y305654D03*
X386560Y283154D03*
Y288654D03*
X376760Y300154D03*
Y305654D03*
X381660Y300154D03*
Y305654D03*
X366960Y300154D03*
Y305654D03*
X371860Y300154D03*
Y305654D03*
X381660Y283154D03*
Y288654D03*
X371860Y283154D03*
Y288654D03*
X366960Y283154D03*
Y288654D03*
X376760Y283154D03*
Y288654D03*
X386560Y300154D03*
Y305654D03*
X396360Y300154D03*
Y305654D03*
Y283154D03*
Y288654D03*
X401260Y300154D03*
Y305654D03*
Y283154D03*
Y288654D03*
X391460Y283154D03*
Y288654D03*
X411192Y318900D03*
Y313400D03*
X421789Y274654D03*
Y269154D03*
X446563Y299154D03*
Y304654D03*
X448298Y287841D03*
Y282341D03*
X420860Y300154D03*
Y305654D03*
Y283000D03*
Y288500D03*
X440860Y283154D03*
Y288654D03*
X430860Y283154D03*
Y288654D03*
X435860Y283154D03*
Y288654D03*
X426648Y299341D03*
Y304841D03*
X425860Y283154D03*
Y288654D03*
X451463Y299154D03*
Y304654D03*
X436648Y299341D03*
Y304841D03*
X453298Y287841D03*
Y282341D03*
X431648Y299341D03*
Y304841D03*
X441663Y299154D03*
Y304654D03*
X426192Y318900D03*
Y313400D03*
X451192Y318900D03*
Y313400D03*
X436192Y318900D03*
Y313400D03*
X431192Y318900D03*
Y313400D03*
X441192Y318900D03*
Y313400D03*
X446192Y318900D03*
Y313400D03*
X427115Y328713D03*
Y334213D03*
X422207Y328713D03*
Y334213D03*
X458148Y314841D03*
Y320341D03*
X421192Y318900D03*
Y313400D03*
X637000Y244000D03*
Y249500D03*
Y239000D03*
Y233500D03*
X665550Y516300D03*
Y521800D03*
X719100Y572000D03*
Y577500D03*
X824000Y196792D03*
Y202292D03*
X844500Y238480D03*
Y232980D03*
Y242980D03*
Y248480D03*
Y271500D03*
Y277000D03*
Y303200D03*
Y308700D03*
Y334750D03*
Y340250D03*
X845900Y366300D03*
Y371800D03*
X1031268Y300154D03*
Y305654D03*
Y283154D03*
Y288654D03*
X1021468Y315654D03*
Y321154D03*
X1026368Y315654D03*
Y321154D03*
X1016568Y315604D03*
Y321104D03*
X1031300Y318900D03*
Y313400D03*
X1032021Y324585D03*
Y330085D03*
X1021468Y283154D03*
Y288654D03*
X1016568Y300154D03*
Y305654D03*
Y283154D03*
Y288654D03*
X1026368Y300154D03*
Y305654D03*
X1021468Y300154D03*
Y305654D03*
X1026368Y283154D03*
Y288654D03*
X1061597Y274654D03*
Y269154D03*
X1071397Y274654D03*
Y269154D03*
X1066497Y274654D03*
Y269154D03*
X1056697Y274654D03*
Y269154D03*
X1051756Y274841D03*
Y269341D03*
X1046856Y274841D03*
Y269341D03*
X1091271Y299154D03*
Y304654D03*
X1096171Y299154D03*
Y304654D03*
X1090468Y283154D03*
Y288654D03*
X1081256Y299341D03*
Y304841D03*
X1086256Y299341D03*
Y304841D03*
X1085468Y283154D03*
Y288654D03*
X1080468Y283154D03*
Y288654D03*
X1076256Y299341D03*
Y304841D03*
X1075468Y283154D03*
Y288654D03*
X1075800Y318900D03*
Y313400D03*
X1080800Y318900D03*
Y313400D03*
X1085800Y318900D03*
Y313400D03*
X1095800Y318900D03*
Y313400D03*
X1090800Y318900D03*
Y313400D03*
X1080445Y328343D03*
Y333843D03*
X1065800Y318900D03*
Y313400D03*
X1046000Y318900D03*
Y313400D03*
X1041100Y318900D03*
Y313400D03*
X1036200Y318900D03*
Y313400D03*
X1055800Y318900D03*
Y313400D03*
X1050900Y318900D03*
Y313400D03*
X1062015Y328713D03*
Y334213D03*
X1066915Y328713D03*
Y334213D03*
X1071815Y328713D03*
Y334213D03*
X1052200Y328200D03*
Y333700D03*
X1057115Y328713D03*
Y334213D03*
X1047300Y328200D03*
Y333700D03*
X1037500Y328000D03*
Y333500D03*
X1042400Y328200D03*
Y333700D03*
X1070468Y283000D03*
Y288500D03*
X1065568Y300154D03*
Y305654D03*
X1065468Y283000D03*
Y288500D03*
X1070468Y300154D03*
Y305654D03*
X1045968Y300154D03*
Y305654D03*
Y283154D03*
Y288654D03*
X1041068Y300154D03*
Y305654D03*
Y283154D03*
Y288654D03*
X1036168Y300154D03*
Y305654D03*
Y283154D03*
Y288654D03*
X1060668Y300154D03*
Y305654D03*
X1050868Y300154D03*
Y305654D03*
X1055768Y300154D03*
Y305654D03*
X1060468Y283000D03*
Y288500D03*
X1055768Y283154D03*
Y288654D03*
X1050868Y283154D03*
Y288654D03*
X1060800Y318900D03*
Y313400D03*
X1070800Y318900D03*
Y313400D03*
X1101071Y299154D03*
Y304654D03*
X1102906Y287841D03*
Y282341D03*
X1097906Y287841D03*
Y282341D03*
X1100800Y318900D03*
Y313400D03*
X1109356Y313150D03*
Y318650D03*
X1341634Y100694D03*
Y106194D03*
X1335664Y514096D03*
Y519596D03*
X1320049Y504266D03*
Y509766D03*
X1383506Y22417D03*
Y16917D03*
X1453900Y385100D03*
Y390600D03*
X1455600Y422100D03*
Y427600D03*
X1464600Y524200D03*
Y518700D03*
X1455600Y519000D03*
Y513500D03*
X1450400Y519000D03*
Y513500D03*
X1469600Y524200D03*
Y518700D03*
X1478500Y525500D03*
Y520000D03*
X1487450Y534300D03*
Y539800D03*
X1579700Y517900D03*
Y512400D03*
X1589100Y499750D03*
Y505250D03*
X1574700Y517900D03*
Y512400D03*
X1584000Y606000D03*
Y600500D03*
X1611630Y74134D03*
Y79134D03*
X1607000Y491500D03*
Y497000D03*
X1612000Y491500D03*
Y497000D03*
X1594300Y499750D03*
Y505250D03*
X1599500Y499750D03*
Y505250D03*
X1832000Y157000D03*
Y162500D03*
X1847650Y104640D03*
Y99140D03*
G54D85*
X104000Y243000D03*
Y254000D03*
X128450Y118700D03*
Y129700D03*
X727500Y93000D03*
Y104000D03*
X758603Y506177D03*
Y495177D03*
X1512959Y277400D03*
Y266400D03*
X1889400Y77300D03*
Y88300D03*
G54D169*
X1260765Y451319D03*
X1253522Y445355D03*
G54D94*
X62250Y291105D03*
Y293075D03*
Y295045D03*
Y297015D03*
Y298985D03*
Y300955D03*
Y302925D03*
Y304895D03*
G54D259*
X1694000Y610000D03*
G54D295*
X1854501Y195587D03*
X1859854Y501441D03*
Y525063D03*
X1952756Y589960D03*
X1944882Y582086D03*
X1952756D03*
X1944882Y574212D03*
X1952756D03*
X1944882Y566338D03*
X1952756D03*
X1944882Y558464D03*
Y589960D03*
Y605708D03*
X1952756D03*
X1944882Y597834D03*
X1952756D03*
G54D58*
X48700Y250260D03*
X29000D03*
X48700Y261300D03*
X29000D03*
G54D187*
X1391987Y482515D03*
X1404310Y492405D03*
G54D286*
X1860500Y80585D03*
G54D68*
X15187Y494150D03*
X13612D03*
X12037D03*
X10462D03*
X8887D03*
X7313D03*
X5738D03*
X4163D03*
X2588D03*
X1013D03*
X662163Y253350D03*
X660588D03*
X659013D03*
X673187D03*
X671612D03*
X670037D03*
X668462D03*
X666887D03*
X665313D03*
X663738D03*
X1364087Y50850D03*
X1362512D03*
X1360937D03*
X1359362D03*
X1357787D03*
X1356213D03*
X1354638D03*
X1353063D03*
X1351488D03*
X1349913D03*
G54D188*
X1351800Y491619D03*
X1565079Y129375D03*
X1628655Y424800D03*
X1642515D03*
X1702140Y146363D03*
X1691776Y144438D03*
X1701890Y113250D03*
X1695119Y111254D03*
X1760339Y153550D03*
X1758228Y148550D03*
X1759589Y138950D03*
X1763217Y134550D03*
X1760240Y130050D03*
X1761298Y143850D03*
X1756589Y121000D03*
G54D269*
X1743680Y505270D03*
Y515070D03*
G54D197*
X1445300Y419350D03*
X1439000Y427618D03*
Y419350D03*
X1445300Y427618D03*
X1863750Y168234D03*
X1870050Y159966D03*
Y168234D03*
X1863750Y159966D03*
X1905450Y133010D03*
X1911750Y124742D03*
Y133010D03*
X1905450Y124742D03*
G54D179*
X1281987Y215066D03*
G54D296*
X1887327Y511202D03*
X1929453Y532541D03*
G54D86*
X105300Y272900D03*
X101550Y281400D03*
X97800Y272900D03*
X106200Y303900D03*
X98700D03*
X102450Y312400D03*
X1217275Y127924D03*
X1224775D03*
X1221025Y136424D03*
X1564831Y331926D03*
X1572331D03*
X1568581Y323426D03*
X1652485Y207858D03*
X1659985D03*
X1656235Y199358D03*
X1871150Y565850D03*
X1867400Y574350D03*
X1874900D03*
X1933500Y540000D03*
X1926000D03*
X1929750Y548500D03*
G54D95*
X64605Y307250D03*
X66575D03*
X68545D03*
X70515D03*
X72485D03*
X74455D03*
X76425D03*
X78395D03*
G54D77*
X107249Y105000D03*
X102328D03*
X97406D03*
X92485D03*
X87564D03*
X82643D03*
X77721D03*
G54D278*
X1787000Y135500D03*
Y143500D03*
X1882660Y540663D03*
X1890660D03*
X1905100Y538000D03*
X1913100D03*
G54D287*
X1860500Y87800D03*
G54D59*
X48700Y255780D03*
X29000D03*
G54D69*
X-1550Y496713D03*
Y498288D03*
Y499863D03*
Y501438D03*
Y503013D03*
Y504587D03*
Y506162D03*
Y507737D03*
Y509312D03*
Y510887D03*
X656450Y255913D03*
Y257488D03*
Y259063D03*
Y260638D03*
Y262213D03*
Y263787D03*
Y265362D03*
Y266937D03*
Y268512D03*
Y270087D03*
X1347350Y53413D03*
Y54988D03*
Y56563D03*
Y58138D03*
Y59713D03*
Y61287D03*
Y62862D03*
Y64437D03*
Y66012D03*
Y67587D03*
G54D87*
X84419Y327900D03*
X82450Y332500D03*
X86387Y327900D03*
Y332500D03*
X84419D03*
G54D279*
X1791000Y115500D03*
Y108500D03*
G54D78*
X72800Y105000D03*
G54D96*
X80750Y304895D03*
Y302925D03*
Y300955D03*
Y298985D03*
Y297015D03*
Y295045D03*
Y293075D03*
Y291105D03*
G54D297*
X1894689Y518328D03*
G54D288*
X1856354Y84433D03*
Y96430D03*
G54D189*
X1405750Y568569D03*
Y585891D03*
G54D198*
X1430570Y457961D03*
G54D199*
X1421619Y461733D03*
X1412123Y465283D03*
G54D289*
X1889906Y96662D03*
X1900406D03*
G54D88*
X82450Y328000D03*
G54D79*
X81500Y127000D03*
Y118000D03*
X95500Y127500D03*
Y118500D03*
X88500Y127000D03*
Y118000D03*
X1573000Y303500D03*
Y312500D03*
X1728000Y82000D03*
Y73000D03*
X1889000Y575700D03*
Y568300D03*
X1891560Y575700D03*
Y568300D03*
X1886440Y575700D03*
Y568300D03*
X1926400Y603700D03*
Y594700D03*
G54D298*
X1851504Y497504D03*
X1868204Y505378D03*
X1851504D03*
X1868204Y513252D03*
X1851504D03*
X1868204Y521126D03*
X1851504D03*
X1868204Y497504D03*
Y529000D03*
X1851504D03*
G54D97*
X79477Y403180D03*
X100477D03*
X79473Y431271D03*
X100473D03*
X78900Y498750D03*
X57900D03*
X730000Y341500D03*
Y370500D03*
X751000Y341500D03*
Y370500D03*
X1392050Y61959D03*
X1413050D03*
G54D299*
X1887327Y532541D03*
X1929453Y511202D03*
G54D89*
X52900Y290500D03*
Y283500D03*
X112600Y170300D03*
Y163300D03*
X655500Y19000D03*
Y12000D03*
X659950Y517400D03*
Y524400D03*
X653450Y517400D03*
Y524400D03*
X656099Y582993D03*
Y575993D03*
X721500Y59500D03*
Y52500D03*
X721900Y544100D03*
Y537100D03*
X729000Y52500D03*
Y59500D03*
X729600Y537150D03*
Y544150D03*
X1302500Y57400D03*
Y50400D03*
X1314367Y504500D03*
Y511500D03*
X1307767Y504500D03*
Y511500D03*
X1303000Y584500D03*
Y591500D03*
Y597500D03*
Y604500D03*
X1382000Y119500D03*
Y112500D03*
X1389700D03*
Y119500D03*
X1376500Y524500D03*
X1384500D03*
X1376500Y531500D03*
X1384500D03*
X1466950Y532550D03*
Y539550D03*
X1512000Y260100D03*
Y253100D03*
X1474350Y532350D03*
Y539350D03*
X1500850Y534200D03*
Y541200D03*
X1493350Y534200D03*
Y541200D03*
X1527440Y542300D03*
Y549300D03*
X1729700Y514000D03*
Y507000D03*
X1761700Y516900D03*
Y509900D03*
G54D98*
X67839Y375400D03*
X69413D03*
X70988D03*
X72563D03*
X74138D03*
X75713D03*
X77287D03*
X78862D03*
X80437D03*
X82012D03*
X83587D03*
X85161D03*
X716839Y286400D03*
X718413D03*
X719988D03*
X721563D03*
X723138D03*
X724713D03*
X726287D03*
X727862D03*
X729437D03*
X731012D03*
X732587D03*
X734161D03*
G54D99*
X87900Y372661D03*
Y371087D03*
Y369512D03*
Y367937D03*
Y366362D03*
Y364787D03*
Y363213D03*
Y361638D03*
Y360063D03*
Y358488D03*
Y356913D03*
Y355339D03*
X736900Y278937D03*
Y277362D03*
Y275787D03*
Y274213D03*
Y272638D03*
Y271063D03*
Y269488D03*
Y267913D03*
Y266339D03*
Y283661D03*
Y282087D03*
Y280512D03*
M02*
